G04 ================== begin FILE IDENTIFICATION RECORD ==================*
G04 Layout Name:  t6m_pdb_d_0928_1400_274.brd*
G04 Film Name:    panel*
G04 File Format:  Gerber RS274X*
G04 File Origin:  Cadence Allegro 16.3-S048*
G04 Origin Date:  Tue Nov 26 11:01:52 2013*
G04 *
G04 Layer:  MANUFACTURING/PHOTOPLOT_OUTLINE*
G04 Layer:  DRAWING FORMAT/TITLE_BLOCK*
G04 Layer:  DRAWING FORMAT/TITLE_DATA_PANEL*
G04 Layer:  BOARD GEOMETRY/ASSEMBLY_NOTES*
G04 *
G04 Offset:    (0.00 0.00)*
G04 Mirror:    No*
G04 Mode:      Positive*
G04 Rotation:  0*
G04 FullContactRelief:  No*
G04 UndefLineWidth:     6.00*
G04 ================== end FILE IDENTIFICATION RECORD ====================*
%FSLAX25Y25*MOIN*%
%IR0*IPPOS*OFA0.00000B0.00000*MIA0B0*SFA1.00000B1.00000*%
%ADD10C,.006*%
G75*
%LPD*%
G75*
G36*
G01X773475Y1883734D02*
G02I-1969J0D01*
G37*
G54D10*
G01X-723776Y2987387D02*
Y-376795D01*
Y-489221D01*
X1782976D01*
Y-376795D01*
Y2987387D01*
X-723776D01*
G01X-112205Y2086614D02*
X-405512D01*
G03X-413386Y2078740I0J-7874D01*
G01Y7874D01*
G03X-405512Y0I7874J0D01*
G01X-112205D01*
G03X-106299Y5905I0J5906D01*
G01Y9842D01*
G02X-100394Y15748I5905J1D01*
G01X-13780D01*
G03X-7874Y21653I1J5905D01*
G01Y2064960D01*
G03X-13780Y2070866I-5906J0D01*
G01X-100394D01*
G02X-106299Y2076771I0J5905D01*
G01Y2080708D01*
G03X-112205Y2086614I-5906J0D01*
G01X-413386Y2081740D02*
Y2122967D01*
G01X-77037Y2119967D02*
X-413386D01*
G01X-408386Y2120967D02*
X-413386Y2119967D01*
X-408386Y2118967D01*
Y2120967D01*
G01X-352403Y939713D02*
X-98451D01*
Y1481750D01*
G01X-241811Y1139713D02*
X-98451D01*
G01X-24487Y2119967D02*
X405512D01*
G01X-4000Y-62500D02*
Y-137500D01*
X496000D01*
Y-62500D01*
X-4000D01*
G01X104331Y0D02*
X397638D01*
G03X405512Y7874I0J7874D01*
G01Y2078740D01*
G03X397638Y2086614I-7874J0D01*
G01X104331D01*
G03X98425Y2080709I0J-5906D01*
G01Y2076772D01*
G02X92520Y2070866I-5905J-1D01*
G01X5906D01*
G03X0Y2064961I-1J-5905D01*
G01Y21654D01*
G03X5906Y15748I5906J0D01*
G01X92520D01*
G02X98425Y9843I0J-5905D01*
G01Y5906D01*
G03X104331Y0I5906J0D01*
G01X-7874Y116184D02*
G02X0I3937J0D01*
G01X-7874Y135870D02*
G03X0I3937J0D01*
G01X-7874Y279584D02*
G02X0I3937J0D01*
G01X-7874Y299270D02*
G03X0I3937J0D01*
G01X-7874Y462534D02*
G03X0I3937J0D01*
G01X-7874Y442848D02*
G02X0I3937J0D01*
G01X-7874Y606272D02*
G02X0I3937J0D01*
G01X-7874Y625958D02*
G03X0I3937J0D01*
G01X-7874Y769584D02*
G02X0I3937J0D01*
G01X-7874Y789270D02*
G03X0I3937J0D01*
G01X-7874Y952670D02*
G03X0I3937J0D01*
G01X-7874Y932984D02*
G02X0I3937J0D01*
G01X-7874Y1096248D02*
G02X0I3937J0D01*
G01X-7874Y1115934D02*
G03X0I3937J0D01*
G01X-7874Y1259672D02*
G02X0I3937J0D01*
G01X-7874Y1279358D02*
G03X0I3937J0D01*
G01X-7874Y1432984D02*
G02X0I3937J0D01*
G01X-7874Y1452670D02*
G03X0I3937J0D01*
G01X-7874Y1596248D02*
G02X0I3937J0D01*
G01X-7874Y1615934D02*
G03X0I3937J0D01*
G01X-7874Y1759672D02*
G02X0I3937J0D01*
G01X-7874Y1779358D02*
G03X0I3937J0D01*
G01X-7874Y1950848D02*
G02X0I3937J0D01*
G01X-7874Y1970534D02*
G03X0I3937J0D01*
G01X8000Y-127500D02*
Y-132500D01*
G01X6543Y-127500D02*
X9457D01*
G01X14367Y-132500D02*
X11833D01*
Y-127500D01*
X14367D01*
G01X13353Y-129917D02*
X11833D01*
G01X16933Y-127500D02*
Y-132500D01*
X19467D01*
G01X23300Y-132667D02*
X23173Y-132583D01*
Y-132417D01*
X23300Y-132333D01*
X23427Y-132417D01*
Y-132583D01*
X23300Y-132667D01*
G01Y-130417D02*
X23173Y-130333D01*
Y-130167D01*
X23300Y-130083D01*
X23427Y-130167D01*
Y-130333D01*
X23300Y-130417D01*
G01X28083Y-134167D02*
X27450Y-133333D01*
X27133Y-132500D01*
Y-129167D01*
X27450Y-128333D01*
X28083Y-127500D01*
G01X33500D02*
X32993Y-127667D01*
X32613Y-128083D01*
X32360Y-128583D01*
X32170Y-129250D01*
X32107Y-130000D01*
X32170Y-130750D01*
X32360Y-131417D01*
X32613Y-131917D01*
X32993Y-132333D01*
X33500Y-132500D01*
X34007Y-132333D01*
X34387Y-131917D01*
X34640Y-131417D01*
X34830Y-130750D01*
X34893Y-130000D01*
X34830Y-129250D01*
X34640Y-128583D01*
X34387Y-128083D01*
X34007Y-127667D01*
X33500Y-127500D01*
G01X37207Y-131500D02*
X37587Y-132083D01*
X38093Y-132417D01*
X38663Y-132500D01*
X39170Y-132417D01*
X39677Y-132000D01*
X39993Y-131500D01*
X40057Y-131000D01*
X39930Y-130417D01*
X39487Y-130000D01*
X39043Y-129833D01*
X38473D01*
G01X39043D02*
X39423Y-129583D01*
X39740Y-129167D01*
X39867Y-128667D01*
X39740Y-128167D01*
X39423Y-127750D01*
X38853Y-127500D01*
X38283Y-127583D01*
X37713Y-127917D01*
G01X44017Y-134167D02*
X44650Y-133333D01*
X44967Y-132500D01*
Y-129167D01*
X44650Y-128333D01*
X44017Y-127500D01*
G01X47407Y-131500D02*
X47787Y-132083D01*
X48293Y-132417D01*
X48863Y-132500D01*
X49370Y-132417D01*
X49877Y-132000D01*
X50193Y-131500D01*
X50257Y-131000D01*
X50130Y-130417D01*
X49687Y-130000D01*
X49243Y-129833D01*
X48673D01*
G01X49243D02*
X49623Y-129583D01*
X49940Y-129167D01*
X50067Y-128667D01*
X49940Y-128167D01*
X49623Y-127750D01*
X49053Y-127500D01*
X48483Y-127583D01*
X47913Y-127917D01*
G01X52697Y-128333D02*
X53077Y-127833D01*
X53520Y-127583D01*
X54027Y-127500D01*
X54660Y-127667D01*
X55103Y-128083D01*
X55230Y-128583D01*
X55167Y-129083D01*
X54913Y-129500D01*
X53647Y-130333D01*
X53077Y-130917D01*
X52697Y-131750D01*
X52570Y-132500D01*
X55230D01*
G01X58873D02*
X59000Y-131417D01*
X59190Y-130500D01*
X59443Y-129667D01*
X59760Y-128750D01*
X60267Y-127500D01*
X57733D01*
G01X63277Y-130833D02*
X64923D01*
G01X67997Y-128333D02*
X68377Y-127833D01*
X68820Y-127583D01*
X69327Y-127500D01*
X69960Y-127667D01*
X70403Y-128083D01*
X70530Y-128583D01*
X70467Y-129083D01*
X70213Y-129500D01*
X68947Y-130333D01*
X68377Y-130917D01*
X67997Y-131750D01*
X67870Y-132500D01*
X70530D01*
G01X72907Y-131500D02*
X73287Y-132083D01*
X73793Y-132417D01*
X74363Y-132500D01*
X74870Y-132417D01*
X75377Y-132000D01*
X75693Y-131500D01*
X75757Y-131000D01*
X75630Y-130417D01*
X75187Y-130000D01*
X74743Y-129833D01*
X74173D01*
G01X74743D02*
X75123Y-129583D01*
X75440Y-129167D01*
X75567Y-128667D01*
X75440Y-128167D01*
X75123Y-127750D01*
X74553Y-127500D01*
X73983Y-127583D01*
X73413Y-127917D01*
G01X80160Y-132500D02*
Y-127500D01*
X77817Y-131083D01*
X80983D01*
G01X83107Y-131750D02*
X83487Y-132167D01*
X83930Y-132417D01*
X84500Y-132500D01*
X85070Y-132333D01*
X85513Y-132000D01*
X85830Y-131417D01*
X85893Y-130750D01*
X85767Y-130083D01*
X85450Y-129667D01*
X85007Y-129333D01*
X84563Y-129250D01*
X84120Y-129333D01*
X83550Y-129667D01*
X83740Y-127500D01*
X85450D01*
G01X93497Y-132500D02*
Y-127500D01*
X95903D01*
G01X95017Y-129917D02*
X93497D01*
G01X98217Y-132500D02*
X99800Y-127500D01*
X101383Y-132500D01*
G01X100813Y-130750D02*
X98787D01*
G01X103570Y-132500D02*
X106230Y-127500D01*
G01X103570D02*
X106230Y-132500D01*
G01X110000Y-132667D02*
X109873Y-132583D01*
Y-132417D01*
X110000Y-132333D01*
X110127Y-132417D01*
Y-132583D01*
X110000Y-132667D01*
G01Y-130417D02*
X109873Y-130333D01*
Y-130167D01*
X110000Y-130083D01*
X110127Y-130167D01*
Y-130333D01*
X110000Y-130417D01*
G01X114783Y-134167D02*
X114150Y-133333D01*
X113833Y-132500D01*
Y-129167D01*
X114150Y-128333D01*
X114783Y-127500D01*
G01X120200D02*
X119693Y-127667D01*
X119313Y-128083D01*
X119060Y-128583D01*
X118870Y-129250D01*
X118807Y-130000D01*
X118870Y-130750D01*
X119060Y-131417D01*
X119313Y-131917D01*
X119693Y-132333D01*
X120200Y-132500D01*
X120707Y-132333D01*
X121087Y-131917D01*
X121340Y-131417D01*
X121530Y-130750D01*
X121593Y-130000D01*
X121530Y-129250D01*
X121340Y-128583D01*
X121087Y-128083D01*
X120707Y-127667D01*
X120200Y-127500D01*
G01X123907Y-131500D02*
X124287Y-132083D01*
X124793Y-132417D01*
X125363Y-132500D01*
X125870Y-132417D01*
X126377Y-132000D01*
X126693Y-131500D01*
X126757Y-131000D01*
X126630Y-130417D01*
X126187Y-130000D01*
X125743Y-129833D01*
X125173D01*
G01X125743D02*
X126123Y-129583D01*
X126440Y-129167D01*
X126567Y-128667D01*
X126440Y-128167D01*
X126123Y-127750D01*
X125553Y-127500D01*
X124983Y-127583D01*
X124413Y-127917D01*
G01X130717Y-134167D02*
X131350Y-133333D01*
X131667Y-132500D01*
Y-129167D01*
X131350Y-128333D01*
X130717Y-127500D01*
G01X134107Y-131500D02*
X134487Y-132083D01*
X134993Y-132417D01*
X135563Y-132500D01*
X136070Y-132417D01*
X136577Y-132000D01*
X136893Y-131500D01*
X136957Y-131000D01*
X136830Y-130417D01*
X136387Y-130000D01*
X135943Y-129833D01*
X135373D01*
G01X135943D02*
X136323Y-129583D01*
X136640Y-129167D01*
X136767Y-128667D01*
X136640Y-128167D01*
X136323Y-127750D01*
X135753Y-127500D01*
X135183Y-127583D01*
X134613Y-127917D01*
G01X139523Y-131917D02*
X139967Y-132333D01*
X140473Y-132500D01*
X140980Y-132333D01*
X141423Y-131833D01*
X141740Y-131083D01*
X141867Y-130333D01*
Y-129417D01*
X141740Y-128667D01*
X141423Y-128000D01*
X141043Y-127667D01*
X140600Y-127500D01*
X140093Y-127667D01*
X139713Y-128000D01*
X139460Y-128500D01*
X139333Y-129167D01*
X139460Y-129750D01*
X139777Y-130333D01*
X140157Y-130667D01*
X140600Y-130750D01*
X141107Y-130583D01*
X141487Y-130167D01*
X141867Y-129417D01*
G01X145573Y-132500D02*
X145700Y-131417D01*
X145890Y-130500D01*
X146143Y-129667D01*
X146460Y-128750D01*
X146967Y-127500D01*
X144433D01*
G01X149977Y-130833D02*
X151623D01*
G01X154507Y-131500D02*
X154887Y-132083D01*
X155393Y-132417D01*
X155963Y-132500D01*
X156470Y-132417D01*
X156977Y-132000D01*
X157293Y-131500D01*
X157357Y-131000D01*
X157230Y-130417D01*
X156787Y-130000D01*
X156343Y-129833D01*
X155773D01*
G01X156343D02*
X156723Y-129583D01*
X157040Y-129167D01*
X157167Y-128667D01*
X157040Y-128167D01*
X156723Y-127750D01*
X156153Y-127500D01*
X155583Y-127583D01*
X155013Y-127917D01*
G01X159797Y-130417D02*
X160240Y-129833D01*
X160620Y-129500D01*
X161127Y-129333D01*
X161570Y-129500D01*
X161887Y-129833D01*
X162140Y-130333D01*
X162203Y-130917D01*
X162140Y-131417D01*
X161887Y-131917D01*
X161507Y-132333D01*
X161063Y-132500D01*
X160557Y-132333D01*
X160113Y-131833D01*
X159860Y-131083D01*
X159797Y-130250D01*
X159923Y-129167D01*
X160113Y-128583D01*
X160430Y-128000D01*
X160873Y-127583D01*
X161317Y-127500D01*
X161760Y-127667D01*
X162077Y-128083D01*
G01X166100Y-132500D02*
Y-127500D01*
X165340Y-128500D01*
G01Y-132500D02*
X166860D01*
G01X171960D02*
Y-127500D01*
X169617Y-131083D01*
X172783D01*
G01X332992Y1474272D02*
X79040D01*
Y932235D01*
G01X222400Y1274272D02*
X79040D01*
G01X191000Y-62500D02*
Y-137500D01*
G01Y-112500D02*
X294000D01*
Y-87500D01*
G01X191000D02*
X294000D01*
G01X301507Y-122500D02*
Y-117500D01*
X302773D01*
X303280Y-117750D01*
X303660Y-118083D01*
X303977Y-118583D01*
X304230Y-119167D01*
X304293Y-120000D01*
X304230Y-120833D01*
X303977Y-121417D01*
X303660Y-121917D01*
X303280Y-122250D01*
X302773Y-122500D01*
X301507D01*
G01X306417D02*
X308000Y-117500D01*
X309583Y-122500D01*
G01X309013Y-120750D02*
X306987D01*
G01X313100Y-117500D02*
Y-122500D01*
G01X311643Y-117500D02*
X314557D01*
G01X319467Y-122500D02*
X316933D01*
Y-117500D01*
X319467D01*
G01X318453Y-119917D02*
X316933D01*
G01X323300Y-122667D02*
X323173Y-122583D01*
Y-122417D01*
X323300Y-122333D01*
X323427Y-122417D01*
Y-122583D01*
X323300Y-122667D01*
G01Y-120417D02*
X323173Y-120333D01*
Y-120167D01*
X323300Y-120083D01*
X323427Y-120167D01*
Y-120333D01*
X323300Y-120417D01*
G01X296000Y-62500D02*
Y-137500D01*
G01X294000Y-62500D02*
Y-137500D01*
G01X301633Y-97500D02*
Y-92500D01*
X303153D01*
X303660Y-92750D01*
X304040Y-93333D01*
X304167Y-94000D01*
X304040Y-94667D01*
X303723Y-95167D01*
X303153Y-95417D01*
X301633D01*
G01X306860Y-97667D02*
X309140Y-92500D01*
G01X311643Y-97500D02*
Y-92500D01*
X314557Y-97500D01*
Y-92500D01*
G01X318200Y-97667D02*
X318073Y-97583D01*
Y-97417D01*
X318200Y-97333D01*
X318327Y-97417D01*
Y-97583D01*
X318200Y-97667D01*
G01Y-95417D02*
X318073Y-95333D01*
Y-95167D01*
X318200Y-95083D01*
X318327Y-95167D01*
Y-95333D01*
X318200Y-95417D01*
G01X296000Y-112500D02*
X496000D01*
G01X301633Y-72500D02*
Y-67500D01*
X303153D01*
X303660Y-67750D01*
X304040Y-68333D01*
X304167Y-69000D01*
X304040Y-69667D01*
X303723Y-70167D01*
X303153Y-70417D01*
X301633D01*
G01X306733Y-72500D02*
Y-67500D01*
X308317D01*
X308823Y-67750D01*
X309140Y-68083D01*
X309267Y-68750D01*
X309140Y-69417D01*
X308760Y-69833D01*
X308317Y-70083D01*
X306733D01*
G01X308317D02*
X309267Y-72500D01*
G01X313100D02*
X312593Y-72417D01*
X312150Y-72083D01*
X311770Y-71583D01*
X311517Y-71000D01*
X311390Y-70333D01*
Y-69667D01*
X311517Y-69000D01*
X311770Y-68417D01*
X312150Y-67917D01*
X312593Y-67583D01*
X313100Y-67500D01*
X313607Y-67583D01*
X314050Y-67917D01*
X314430Y-68417D01*
X314683Y-69000D01*
X314810Y-69667D01*
Y-70333D01*
X314683Y-71000D01*
X314430Y-71583D01*
X314050Y-72083D01*
X313607Y-72417D01*
X313100Y-72500D01*
G01X316933Y-71500D02*
X317250Y-72000D01*
X317630Y-72333D01*
X318073Y-72500D01*
X318580Y-72333D01*
X318960Y-72000D01*
X319340Y-71500D01*
X319467Y-70833D01*
Y-67500D01*
G01X324567Y-72500D02*
X322033D01*
Y-67500D01*
X324567D01*
G01X323553Y-69917D02*
X322033D01*
G01X329793Y-67917D02*
X329413Y-67667D01*
X328970Y-67500D01*
X328463D01*
X327893Y-67750D01*
X327450Y-68167D01*
X327133Y-68667D01*
X326880Y-69500D01*
X326817Y-70250D01*
X326943Y-71000D01*
X327133Y-71500D01*
X327513Y-72000D01*
X327957Y-72333D01*
X328400Y-72500D01*
X328843D01*
X329287Y-72333D01*
X329667Y-72083D01*
X329983Y-71750D01*
G01X333500Y-67500D02*
Y-72500D01*
G01X332043Y-67500D02*
X334957D01*
G01X338600Y-72667D02*
X338473Y-72583D01*
Y-72417D01*
X338600Y-72333D01*
X338727Y-72417D01*
Y-72583D01*
X338600Y-72667D01*
G01Y-70417D02*
X338473Y-70333D01*
Y-70167D01*
X338600Y-70083D01*
X338727Y-70167D01*
Y-70333D01*
X338600Y-70417D01*
G01X296000Y-87500D02*
X496000D01*
G01X411000Y-112500D02*
Y-137500D01*
G01X400638Y0D02*
X496239D01*
G01X405512Y2081740D02*
Y2122967D01*
G01X400638Y2086614D02*
X496239D01*
G01X400512Y2118967D02*
X405512Y2119967D01*
X400512Y2120967D01*
Y2118967D01*
G01X416633Y-122500D02*
Y-117500D01*
X418217D01*
X418723Y-117750D01*
X419040Y-118083D01*
X419167Y-118750D01*
X419040Y-119417D01*
X418660Y-119833D01*
X418217Y-120083D01*
X416633D01*
G01X418217D02*
X419167Y-122500D01*
G01X424267D02*
X421733D01*
Y-117500D01*
X424267D01*
G01X423253Y-119917D02*
X421733D01*
G01X426517Y-117500D02*
X428100Y-122500D01*
X429683Y-117500D01*
G01X433200Y-122667D02*
X433073Y-122583D01*
Y-122417D01*
X433200Y-122333D01*
X433327Y-122417D01*
Y-122583D01*
X433200Y-122667D01*
G01Y-120417D02*
X433073Y-120333D01*
Y-120167D01*
X433200Y-120083D01*
X433327Y-120167D01*
Y-120333D01*
X433200Y-120417D01*
G01X460000Y-112500D02*
Y-137500D01*
G01X493239Y1010054D02*
Y0D01*
G01X492239Y5000D02*
X493239Y0D01*
X494239Y5000D01*
X492239D01*
G01X493239Y1068904D02*
Y2086614D01*
G01X494239Y2081614D02*
X493239Y2086614D01*
X492239Y2081614D01*
X494239D01*
G01X744228Y1845063D02*
X744481Y1845313D01*
X744671Y1845729D01*
X744798Y1846313D01*
X744671Y1846813D01*
X744418Y1847146D01*
X743974Y1847396D01*
X742264D01*
Y1842396D01*
X744354D01*
X744798Y1842729D01*
X745051Y1843229D01*
X745178Y1843813D01*
X745051Y1844396D01*
X744671Y1844896D01*
X744228Y1845063D01*
X742264D01*
G01X747934Y1842396D02*
Y1845729D01*
G01Y1845063D02*
X748251Y1845396D01*
X748568Y1845646D01*
X749011Y1845729D01*
X749328Y1845646D01*
X749708Y1845396D01*
G01X752971Y1844646D02*
X754998D01*
X754808Y1845229D01*
X754491Y1845563D01*
X754048Y1845729D01*
X753604Y1845646D01*
X753224Y1845396D01*
X752971Y1844813D01*
X752844Y1844313D01*
Y1843813D01*
X752971Y1843313D01*
X753288Y1842813D01*
X753668Y1842479D01*
X754111Y1842396D01*
X754554Y1842563D01*
X754998Y1843063D01*
G01X760161Y1842396D02*
Y1845729D01*
G01Y1845146D02*
X759908Y1845479D01*
X759528Y1845646D01*
X759084Y1845729D01*
X758641Y1845563D01*
X758261Y1845229D01*
X758008Y1844729D01*
X757881Y1844063D01*
X758008Y1843396D01*
X758261Y1842896D01*
X758641Y1842563D01*
X759084Y1842396D01*
X759528Y1842479D01*
X759908Y1842729D01*
X760161Y1843063D01*
G01X763044Y1842396D02*
Y1847396D01*
G01X765071Y1845729D02*
X763044Y1843813D01*
G01X763868Y1844563D02*
X765198Y1842396D01*
G01X769221Y1847396D02*
Y1842396D01*
G01X768334Y1845729D02*
X770108D01*
G01X775461Y1842396D02*
Y1845729D01*
G01Y1845146D02*
X775208Y1845479D01*
X774828Y1845646D01*
X774384Y1845729D01*
X773941Y1845563D01*
X773561Y1845229D01*
X773308Y1844729D01*
X773181Y1844063D01*
X773308Y1843396D01*
X773561Y1842896D01*
X773941Y1842563D01*
X774384Y1842396D01*
X774828Y1842479D01*
X775208Y1842729D01*
X775461Y1843063D01*
G01X778281Y1842396D02*
Y1847396D01*
G01Y1844896D02*
X778598Y1845396D01*
X778978Y1845646D01*
X779358Y1845729D01*
X779928Y1845563D01*
X780308Y1845229D01*
X780561Y1844646D01*
Y1843979D01*
X780434Y1843313D01*
X780181Y1842813D01*
X779738Y1842479D01*
X779358Y1842396D01*
X778978Y1842479D01*
X778598Y1842729D01*
X778281Y1843146D01*
G01X784521Y1842229D02*
X784394Y1842313D01*
Y1842479D01*
X784521Y1842563D01*
X784648Y1842479D01*
Y1842313D01*
X784521Y1842229D01*
G01Y1844479D02*
X784394Y1844563D01*
Y1844729D01*
X784521Y1844813D01*
X784648Y1844729D01*
Y1844563D01*
X784521Y1844479D01*
G01X819018Y1908926D02*
Y1913926D01*
X821424D01*
G01X820538Y1911509D02*
X819018D01*
G01X825321Y1908926D02*
X824941Y1909009D01*
X824561Y1909343D01*
X824308Y1909926D01*
X824181Y1910593D01*
X824308Y1911259D01*
X824561Y1911843D01*
X824941Y1912176D01*
X825321Y1912259D01*
X825701Y1912176D01*
X826081Y1911843D01*
X826334Y1911259D01*
X826398Y1910593D01*
X826334Y1909926D01*
X826081Y1909343D01*
X825701Y1909009D01*
X825321Y1908926D01*
G01X829534D02*
Y1912259D01*
G01Y1911593D02*
X829851Y1911926D01*
X830168Y1912176D01*
X830611Y1912259D01*
X830928Y1912176D01*
X831308Y1911926D01*
G01X839354Y1908926D02*
Y1913926D01*
X840874D01*
X841381Y1913676D01*
X841761Y1913093D01*
X841888Y1912426D01*
X841761Y1911759D01*
X841444Y1911259D01*
X840874Y1911009D01*
X839354D01*
G01X846861Y1908926D02*
Y1912259D01*
G01Y1911676D02*
X846608Y1912009D01*
X846228Y1912176D01*
X845784Y1912259D01*
X845341Y1912093D01*
X844961Y1911759D01*
X844708Y1911259D01*
X844581Y1910593D01*
X844708Y1909926D01*
X844961Y1909426D01*
X845341Y1909093D01*
X845784Y1908926D01*
X846228Y1909009D01*
X846608Y1909259D01*
X846861Y1909593D01*
G01X849744Y1908926D02*
Y1912259D01*
G01Y1911426D02*
X849998Y1911843D01*
X850378Y1912176D01*
X850884Y1912259D01*
X851328Y1912176D01*
X851708Y1911843D01*
X851898Y1911259D01*
Y1908926D01*
G01X854971Y1911176D02*
X856998D01*
X856808Y1911759D01*
X856491Y1912093D01*
X856048Y1912259D01*
X855604Y1912176D01*
X855224Y1911926D01*
X854971Y1911343D01*
X854844Y1910843D01*
Y1910343D01*
X854971Y1909843D01*
X855288Y1909343D01*
X855668Y1909009D01*
X856111Y1908926D01*
X856554Y1909093D01*
X856998Y1909593D01*
G01X861021Y1908926D02*
Y1913926D01*
G01X871728Y1911593D02*
X871981Y1911843D01*
X872171Y1912259D01*
X872298Y1912843D01*
X872171Y1913343D01*
X871918Y1913676D01*
X871474Y1913926D01*
X869764D01*
Y1908926D01*
X871854D01*
X872298Y1909259D01*
X872551Y1909759D01*
X872678Y1910343D01*
X872551Y1910926D01*
X872171Y1911426D01*
X871728Y1911593D01*
X869764D01*
G01X876321Y1908926D02*
X875941Y1909009D01*
X875561Y1909343D01*
X875308Y1909926D01*
X875181Y1910593D01*
X875308Y1911259D01*
X875561Y1911843D01*
X875941Y1912176D01*
X876321Y1912259D01*
X876701Y1912176D01*
X877081Y1911843D01*
X877334Y1911259D01*
X877398Y1910593D01*
X877334Y1909926D01*
X877081Y1909343D01*
X876701Y1909009D01*
X876321Y1908926D01*
G01X882561D02*
Y1912259D01*
G01Y1911676D02*
X882308Y1912009D01*
X881928Y1912176D01*
X881484Y1912259D01*
X881041Y1912093D01*
X880661Y1911759D01*
X880408Y1911259D01*
X880281Y1910593D01*
X880408Y1909926D01*
X880661Y1909426D01*
X881041Y1909093D01*
X881484Y1908926D01*
X881928Y1909009D01*
X882308Y1909259D01*
X882561Y1909593D01*
G01X885634Y1908926D02*
Y1912259D01*
G01Y1911593D02*
X885951Y1911926D01*
X886268Y1912176D01*
X886711Y1912259D01*
X887028Y1912176D01*
X887408Y1911926D01*
G01X892761Y1913926D02*
Y1908926D01*
G01Y1909676D02*
X892508Y1909259D01*
X892128Y1909009D01*
X891684Y1908926D01*
X891178Y1909093D01*
X890798Y1909509D01*
X890544Y1910009D01*
X890481Y1910593D01*
X890544Y1911176D01*
X890798Y1911676D01*
X891178Y1912093D01*
X891684Y1912259D01*
X892128Y1912176D01*
X892444Y1912009D01*
X892761Y1911676D01*
G01X819018Y1908926D02*
Y1913926D01*
X821424D01*
G01X820538Y1911509D02*
X819018D01*
G01X825321Y1908926D02*
X824941Y1909009D01*
X824561Y1909343D01*
X824308Y1909926D01*
X824181Y1910593D01*
X824308Y1911259D01*
X824561Y1911843D01*
X824941Y1912176D01*
X825321Y1912259D01*
X825701Y1912176D01*
X826081Y1911843D01*
X826334Y1911259D01*
X826398Y1910593D01*
X826334Y1909926D01*
X826081Y1909343D01*
X825701Y1909009D01*
X825321Y1908926D01*
G01X829534D02*
Y1912259D01*
G01Y1911593D02*
X829851Y1911926D01*
X830168Y1912176D01*
X830611Y1912259D01*
X830928Y1912176D01*
X831308Y1911926D01*
G01X839354Y1908926D02*
Y1913926D01*
X840874D01*
X841381Y1913676D01*
X841761Y1913093D01*
X841888Y1912426D01*
X841761Y1911759D01*
X841444Y1911259D01*
X840874Y1911009D01*
X839354D01*
G01X846861Y1908926D02*
Y1912259D01*
G01Y1911676D02*
X846608Y1912009D01*
X846228Y1912176D01*
X845784Y1912259D01*
X845341Y1912093D01*
X844961Y1911759D01*
X844708Y1911259D01*
X844581Y1910593D01*
X844708Y1909926D01*
X844961Y1909426D01*
X845341Y1909093D01*
X845784Y1908926D01*
X846228Y1909009D01*
X846608Y1909259D01*
X846861Y1909593D01*
G01X849744Y1908926D02*
Y1912259D01*
G01Y1911426D02*
X849998Y1911843D01*
X850378Y1912176D01*
X850884Y1912259D01*
X851328Y1912176D01*
X851708Y1911843D01*
X851898Y1911259D01*
Y1908926D01*
G01X854971Y1911176D02*
X856998D01*
X856808Y1911759D01*
X856491Y1912093D01*
X856048Y1912259D01*
X855604Y1912176D01*
X855224Y1911926D01*
X854971Y1911343D01*
X854844Y1910843D01*
Y1910343D01*
X854971Y1909843D01*
X855288Y1909343D01*
X855668Y1909009D01*
X856111Y1908926D01*
X856554Y1909093D01*
X856998Y1909593D01*
G01X861021Y1908926D02*
Y1913926D01*
G01X871728Y1911593D02*
X871981Y1911843D01*
X872171Y1912259D01*
X872298Y1912843D01*
X872171Y1913343D01*
X871918Y1913676D01*
X871474Y1913926D01*
X869764D01*
Y1908926D01*
X871854D01*
X872298Y1909259D01*
X872551Y1909759D01*
X872678Y1910343D01*
X872551Y1910926D01*
X872171Y1911426D01*
X871728Y1911593D01*
X869764D01*
G01X876321Y1908926D02*
X875941Y1909009D01*
X875561Y1909343D01*
X875308Y1909926D01*
X875181Y1910593D01*
X875308Y1911259D01*
X875561Y1911843D01*
X875941Y1912176D01*
X876321Y1912259D01*
X876701Y1912176D01*
X877081Y1911843D01*
X877334Y1911259D01*
X877398Y1910593D01*
X877334Y1909926D01*
X877081Y1909343D01*
X876701Y1909009D01*
X876321Y1908926D01*
G01X882561D02*
Y1912259D01*
G01Y1911676D02*
X882308Y1912009D01*
X881928Y1912176D01*
X881484Y1912259D01*
X881041Y1912093D01*
X880661Y1911759D01*
X880408Y1911259D01*
X880281Y1910593D01*
X880408Y1909926D01*
X880661Y1909426D01*
X881041Y1909093D01*
X881484Y1908926D01*
X881928Y1909009D01*
X882308Y1909259D01*
X882561Y1909593D01*
G01X885634Y1908926D02*
Y1912259D01*
G01Y1911593D02*
X885951Y1911926D01*
X886268Y1912176D01*
X886711Y1912259D01*
X887028Y1912176D01*
X887408Y1911926D01*
G01X892761Y1913926D02*
Y1908926D01*
G01Y1909676D02*
X892508Y1909259D01*
X892128Y1909009D01*
X891684Y1908926D01*
X891178Y1909093D01*
X890798Y1909509D01*
X890544Y1910009D01*
X890481Y1910593D01*
X890544Y1911176D01*
X890798Y1911676D01*
X891178Y1912093D01*
X891684Y1912259D01*
X892128Y1912176D01*
X892444Y1912009D01*
X892761Y1911676D01*
G01X818828Y1934126D02*
Y1939126D01*
X820094D01*
X820601Y1938876D01*
X820981Y1938543D01*
X821298Y1938043D01*
X821551Y1937459D01*
X821614Y1936626D01*
X821551Y1935793D01*
X821298Y1935209D01*
X820981Y1934709D01*
X820601Y1934376D01*
X820094Y1934126D01*
X818828D01*
G01X825321Y1937459D02*
Y1934126D01*
G01Y1938793D02*
X825194Y1938876D01*
Y1939043D01*
X825321Y1939126D01*
X825448Y1939043D01*
Y1938876D01*
X825321Y1938793D01*
G01X831561Y1934126D02*
Y1937459D01*
G01Y1936876D02*
X831308Y1937209D01*
X830928Y1937376D01*
X830484Y1937459D01*
X830041Y1937293D01*
X829661Y1936959D01*
X829408Y1936459D01*
X829281Y1935793D01*
X829408Y1935126D01*
X829661Y1934626D01*
X830041Y1934293D01*
X830484Y1934126D01*
X830928Y1934209D01*
X831308Y1934459D01*
X831561Y1934793D01*
G01X833621Y1934126D02*
Y1937459D01*
G01Y1936543D02*
X833811Y1936959D01*
X834128Y1937293D01*
X834571Y1937459D01*
X835014Y1937293D01*
X835331Y1936959D01*
X835521Y1936543D01*
Y1934126D01*
G01Y1936543D02*
X835711Y1936959D01*
X836028Y1937293D01*
X836471Y1937459D01*
X836914Y1937293D01*
X837231Y1936959D01*
X837421Y1936459D01*
Y1934126D01*
G01X839671Y1936376D02*
X841698D01*
X841508Y1936959D01*
X841191Y1937293D01*
X840748Y1937459D01*
X840304Y1937376D01*
X839924Y1937126D01*
X839671Y1936543D01*
X839544Y1936043D01*
Y1935543D01*
X839671Y1935043D01*
X839988Y1934543D01*
X840368Y1934209D01*
X840811Y1934126D01*
X841254Y1934293D01*
X841698Y1934793D01*
G01X845721Y1939126D02*
Y1934126D01*
G01X844834Y1937459D02*
X846608D01*
G01X849871Y1936376D02*
X851898D01*
X851708Y1936959D01*
X851391Y1937293D01*
X850948Y1937459D01*
X850504Y1937376D01*
X850124Y1937126D01*
X849871Y1936543D01*
X849744Y1936043D01*
Y1935543D01*
X849871Y1935043D01*
X850188Y1934543D01*
X850568Y1934209D01*
X851011Y1934126D01*
X851454Y1934293D01*
X851898Y1934793D01*
G01X855034Y1934126D02*
Y1937459D01*
G01Y1936793D02*
X855351Y1937126D01*
X855668Y1937376D01*
X856111Y1937459D01*
X856428Y1937376D01*
X856808Y1937126D01*
G01X864728Y1935126D02*
X865108Y1934543D01*
X865614Y1934209D01*
X866184Y1934126D01*
X866691Y1934209D01*
X867198Y1934626D01*
X867514Y1935126D01*
X867578Y1935626D01*
X867451Y1936209D01*
X867008Y1936626D01*
X866564Y1936793D01*
X865994D01*
G01X866564D02*
X866944Y1937043D01*
X867261Y1937459D01*
X867388Y1937959D01*
X867261Y1938459D01*
X866944Y1938876D01*
X866374Y1939126D01*
X865804Y1939043D01*
X865234Y1938709D01*
G01X869321Y1934126D02*
Y1937459D01*
G01Y1936543D02*
X869511Y1936959D01*
X869828Y1937293D01*
X870271Y1937459D01*
X870714Y1937293D01*
X871031Y1936959D01*
X871221Y1936543D01*
Y1934126D01*
G01Y1936543D02*
X871411Y1936959D01*
X871728Y1937293D01*
X872171Y1937459D01*
X872614Y1937293D01*
X872931Y1936959D01*
X873121Y1936459D01*
Y1934126D01*
G01X874421D02*
Y1937459D01*
G01Y1936543D02*
X874611Y1936959D01*
X874928Y1937293D01*
X875371Y1937459D01*
X875814Y1937293D01*
X876131Y1936959D01*
X876321Y1936543D01*
Y1934126D01*
G01Y1936543D02*
X876511Y1936959D01*
X876828Y1937293D01*
X877271Y1937459D01*
X877714Y1937293D01*
X878031Y1936959D01*
X878221Y1936459D01*
Y1934126D01*
G01X885191Y1934793D02*
X885698Y1934376D01*
X886268Y1934126D01*
X886774D01*
X887281Y1934376D01*
X887661Y1934793D01*
X887851Y1935376D01*
X887724Y1935959D01*
X887408Y1936459D01*
X886838Y1936793D01*
X886078Y1936959D01*
X885634Y1937293D01*
X885444Y1937876D01*
X885571Y1938459D01*
X885888Y1938876D01*
X886331Y1939126D01*
X886774D01*
X887218Y1938959D01*
X887598Y1938543D01*
G01X891621Y1934126D02*
X891241Y1934209D01*
X890861Y1934543D01*
X890608Y1935126D01*
X890481Y1935793D01*
X890608Y1936459D01*
X890861Y1937043D01*
X891241Y1937376D01*
X891621Y1937459D01*
X892001Y1937376D01*
X892381Y1937043D01*
X892634Y1936459D01*
X892698Y1935793D01*
X892634Y1935126D01*
X892381Y1934543D01*
X892001Y1934209D01*
X891621Y1934126D01*
G01X896721D02*
Y1939126D01*
G01X902961D02*
Y1934126D01*
G01Y1934876D02*
X902708Y1934459D01*
X902328Y1934209D01*
X901884Y1934126D01*
X901378Y1934293D01*
X900998Y1934709D01*
X900744Y1935209D01*
X900681Y1935793D01*
X900744Y1936376D01*
X900998Y1936876D01*
X901378Y1937293D01*
X901884Y1937459D01*
X902328Y1937376D01*
X902644Y1937209D01*
X902961Y1936876D01*
G01X905971Y1936376D02*
X907998D01*
X907808Y1936959D01*
X907491Y1937293D01*
X907048Y1937459D01*
X906604Y1937376D01*
X906224Y1937126D01*
X905971Y1936543D01*
X905844Y1936043D01*
Y1935543D01*
X905971Y1935043D01*
X906288Y1934543D01*
X906668Y1934209D01*
X907111Y1934126D01*
X907554Y1934293D01*
X907998Y1934793D01*
G01X911134Y1934126D02*
Y1937459D01*
G01Y1936793D02*
X911451Y1937126D01*
X911768Y1937376D01*
X912211Y1937459D01*
X912528Y1937376D01*
X912908Y1937126D01*
G01X915221Y1934126D02*
Y1937459D01*
G01Y1936543D02*
X915411Y1936959D01*
X915728Y1937293D01*
X916171Y1937459D01*
X916614Y1937293D01*
X916931Y1936959D01*
X917121Y1936543D01*
Y1934126D01*
G01Y1936543D02*
X917311Y1936959D01*
X917628Y1937293D01*
X918071Y1937459D01*
X918514Y1937293D01*
X918831Y1936959D01*
X919021Y1936459D01*
Y1934126D01*
G01X923361D02*
Y1937459D01*
G01Y1936876D02*
X923108Y1937209D01*
X922728Y1937376D01*
X922284Y1937459D01*
X921841Y1937293D01*
X921461Y1936959D01*
X921208Y1936459D01*
X921081Y1935793D01*
X921208Y1935126D01*
X921461Y1934626D01*
X921841Y1934293D01*
X922284Y1934126D01*
X922728Y1934209D01*
X923108Y1934459D01*
X923361Y1934793D01*
G01X926371Y1934709D02*
X926688Y1934376D01*
X927131Y1934126D01*
X927511D01*
X927891Y1934293D01*
X928144Y1934543D01*
X928271Y1934876D01*
X928208Y1935376D01*
X927954Y1935626D01*
X926814Y1936126D01*
X926561Y1936709D01*
X926688Y1937126D01*
X926941Y1937376D01*
X927321Y1937459D01*
X927701Y1937376D01*
X928081Y1937126D01*
G01X931344Y1934126D02*
Y1939126D01*
G01X933371Y1937459D02*
X931344Y1935543D01*
G01X932168Y1936293D02*
X933498Y1934126D01*
G01X820221Y1926526D02*
Y1921526D01*
G01X818764Y1926526D02*
X821678D01*
G01X825321Y1921526D02*
X824941Y1921609D01*
X824561Y1921943D01*
X824308Y1922526D01*
X824181Y1923193D01*
X824308Y1923859D01*
X824561Y1924443D01*
X824941Y1924776D01*
X825321Y1924859D01*
X825701Y1924776D01*
X826081Y1924443D01*
X826334Y1923859D01*
X826398Y1923193D01*
X826334Y1922526D01*
X826081Y1921943D01*
X825701Y1921609D01*
X825321Y1921526D01*
G01X829281Y1919859D02*
Y1924859D01*
G01Y1924109D02*
X829598Y1924526D01*
X829914Y1924776D01*
X830421Y1924859D01*
X830864Y1924776D01*
X831308Y1924359D01*
X831498Y1923776D01*
X831561Y1923193D01*
X831498Y1922609D01*
X831308Y1922026D01*
X830928Y1921693D01*
X830421Y1921526D01*
X829978Y1921609D01*
X829534Y1921859D01*
X829281Y1922193D01*
G01X839038Y1921526D02*
X840621Y1926526D01*
X842204Y1921526D01*
G01X841634Y1923276D02*
X839608D01*
G01X844644Y1921526D02*
Y1924859D01*
G01Y1924026D02*
X844898Y1924443D01*
X845278Y1924776D01*
X845784Y1924859D01*
X846228Y1924776D01*
X846608Y1924443D01*
X846798Y1923859D01*
Y1921526D01*
G01X851961Y1926526D02*
Y1921526D01*
G01Y1922276D02*
X851708Y1921859D01*
X851328Y1921609D01*
X850884Y1921526D01*
X850378Y1921693D01*
X849998Y1922109D01*
X849744Y1922609D01*
X849681Y1923193D01*
X849744Y1923776D01*
X849998Y1924276D01*
X850378Y1924693D01*
X850884Y1924859D01*
X851328Y1924776D01*
X851644Y1924609D01*
X851961Y1924276D01*
G01X861528Y1924193D02*
X861781Y1924443D01*
X861971Y1924859D01*
X862098Y1925443D01*
X861971Y1925943D01*
X861718Y1926276D01*
X861274Y1926526D01*
X859564D01*
Y1921526D01*
X861654D01*
X862098Y1921859D01*
X862351Y1922359D01*
X862478Y1922943D01*
X862351Y1923526D01*
X861971Y1924026D01*
X861528Y1924193D01*
X859564D01*
G01X866121Y1921526D02*
X865741Y1921609D01*
X865361Y1921943D01*
X865108Y1922526D01*
X864981Y1923193D01*
X865108Y1923859D01*
X865361Y1924443D01*
X865741Y1924776D01*
X866121Y1924859D01*
X866501Y1924776D01*
X866881Y1924443D01*
X867134Y1923859D01*
X867198Y1923193D01*
X867134Y1922526D01*
X866881Y1921943D01*
X866501Y1921609D01*
X866121Y1921526D01*
G01X871221Y1926526D02*
Y1921526D01*
G01X870334Y1924859D02*
X872108D01*
G01X876321Y1926526D02*
Y1921526D01*
G01X875434Y1924859D02*
X877208D01*
G01X881421Y1921526D02*
X881041Y1921609D01*
X880661Y1921943D01*
X880408Y1922526D01*
X880281Y1923193D01*
X880408Y1923859D01*
X880661Y1924443D01*
X881041Y1924776D01*
X881421Y1924859D01*
X881801Y1924776D01*
X882181Y1924443D01*
X882434Y1923859D01*
X882498Y1923193D01*
X882434Y1922526D01*
X882181Y1921943D01*
X881801Y1921609D01*
X881421Y1921526D01*
G01X884621D02*
Y1924859D01*
G01Y1923943D02*
X884811Y1924359D01*
X885128Y1924693D01*
X885571Y1924859D01*
X886014Y1924693D01*
X886331Y1924359D01*
X886521Y1923943D01*
Y1921526D01*
G01Y1923943D02*
X886711Y1924359D01*
X887028Y1924693D01*
X887471Y1924859D01*
X887914Y1924693D01*
X888231Y1924359D01*
X888421Y1923859D01*
Y1921526D01*
G01X895391Y1922193D02*
X895898Y1921776D01*
X896468Y1921526D01*
X896974D01*
X897481Y1921776D01*
X897861Y1922193D01*
X898051Y1922776D01*
X897924Y1923359D01*
X897608Y1923859D01*
X897038Y1924193D01*
X896278Y1924359D01*
X895834Y1924693D01*
X895644Y1925276D01*
X895771Y1925859D01*
X896088Y1926276D01*
X896531Y1926526D01*
X896974D01*
X897418Y1926359D01*
X897798Y1925943D01*
G01X901821Y1924859D02*
Y1921526D01*
G01Y1926193D02*
X901694Y1926276D01*
Y1926443D01*
X901821Y1926526D01*
X901948Y1926443D01*
Y1926276D01*
X901821Y1926193D01*
G01X908061Y1926526D02*
Y1921526D01*
G01Y1922276D02*
X907808Y1921859D01*
X907428Y1921609D01*
X906984Y1921526D01*
X906478Y1921693D01*
X906098Y1922109D01*
X905844Y1922609D01*
X905781Y1923193D01*
X905844Y1923776D01*
X906098Y1924276D01*
X906478Y1924693D01*
X906984Y1924859D01*
X907428Y1924776D01*
X907744Y1924609D01*
X908061Y1924276D01*
G01X911071Y1923776D02*
X913098D01*
X912908Y1924359D01*
X912591Y1924693D01*
X912148Y1924859D01*
X911704Y1924776D01*
X911324Y1924526D01*
X911071Y1923943D01*
X910944Y1923443D01*
Y1922943D01*
X911071Y1922443D01*
X911388Y1921943D01*
X911768Y1921609D01*
X912211Y1921526D01*
X912654Y1921693D01*
X913098Y1922193D01*
G01X742518Y1946726D02*
Y1951726D01*
X744924D01*
G01X744038Y1949309D02*
X742518D01*
G01X748821Y1950059D02*
Y1946726D01*
G01Y1951393D02*
X748694Y1951476D01*
Y1951643D01*
X748821Y1951726D01*
X748948Y1951643D01*
Y1951476D01*
X748821Y1951393D01*
G01X755061Y1951726D02*
Y1946726D01*
G01Y1947476D02*
X754808Y1947059D01*
X754428Y1946809D01*
X753984Y1946726D01*
X753478Y1946893D01*
X753098Y1947309D01*
X752844Y1947809D01*
X752781Y1948393D01*
X752844Y1948976D01*
X753098Y1949476D01*
X753478Y1949893D01*
X753984Y1950059D01*
X754428Y1949976D01*
X754744Y1949809D01*
X755061Y1949476D01*
G01X757944Y1950059D02*
Y1947726D01*
X758198Y1947143D01*
X758578Y1946809D01*
X759021Y1946726D01*
X759464Y1946809D01*
X759844Y1947143D01*
X760098Y1947726D01*
G01Y1946726D02*
Y1950059D01*
G01X765134Y1949643D02*
X764691Y1949976D01*
X764311Y1950059D01*
X763804Y1949893D01*
X763424Y1949559D01*
X763171Y1948976D01*
X763108Y1948393D01*
X763171Y1947809D01*
X763424Y1947309D01*
X763804Y1946893D01*
X764311Y1946726D01*
X764754Y1946893D01*
X765134Y1947226D01*
G01X769221Y1950059D02*
Y1946726D01*
G01Y1951393D02*
X769094Y1951476D01*
Y1951643D01*
X769221Y1951726D01*
X769348Y1951643D01*
Y1951476D01*
X769221Y1951393D01*
G01X775461Y1946726D02*
Y1950059D01*
G01Y1949476D02*
X775208Y1949809D01*
X774828Y1949976D01*
X774384Y1950059D01*
X773941Y1949893D01*
X773561Y1949559D01*
X773308Y1949059D01*
X773181Y1948393D01*
X773308Y1947726D01*
X773561Y1947226D01*
X773941Y1946893D01*
X774384Y1946726D01*
X774828Y1946809D01*
X775208Y1947059D01*
X775461Y1947393D01*
G01X779421Y1946726D02*
Y1951726D01*
G01X787974Y1946726D02*
Y1951726D01*
X789621Y1947559D01*
X791268Y1951726D01*
Y1946726D01*
G01X795861D02*
Y1950059D01*
G01Y1949476D02*
X795608Y1949809D01*
X795228Y1949976D01*
X794784Y1950059D01*
X794341Y1949893D01*
X793961Y1949559D01*
X793708Y1949059D01*
X793581Y1948393D01*
X793708Y1947726D01*
X793961Y1947226D01*
X794341Y1946893D01*
X794784Y1946726D01*
X795228Y1946809D01*
X795608Y1947059D01*
X795861Y1947393D01*
G01X798934Y1946726D02*
Y1950059D01*
G01Y1949393D02*
X799251Y1949726D01*
X799568Y1949976D01*
X800011Y1950059D01*
X800328Y1949976D01*
X800708Y1949726D01*
G01X803844Y1946726D02*
Y1951726D01*
G01X805871Y1950059D02*
X803844Y1948143D01*
G01X804668Y1948893D02*
X805998Y1946726D01*
G01X810021Y1946559D02*
X809894Y1946643D01*
Y1946809D01*
X810021Y1946893D01*
X810148Y1946809D01*
Y1946643D01*
X810021Y1946559D01*
G01Y1948809D02*
X809894Y1948893D01*
Y1949059D01*
X810021Y1949143D01*
X810148Y1949059D01*
Y1948893D01*
X810021Y1948809D01*
G01X818828Y1946726D02*
Y1951726D01*
X820094D01*
X820601Y1951476D01*
X820981Y1951143D01*
X821298Y1950643D01*
X821551Y1950059D01*
X821614Y1949226D01*
X821551Y1948393D01*
X821298Y1947809D01*
X820981Y1947309D01*
X820601Y1946976D01*
X820094Y1946726D01*
X818828D01*
G01X825321Y1950059D02*
Y1946726D01*
G01Y1951393D02*
X825194Y1951476D01*
Y1951643D01*
X825321Y1951726D01*
X825448Y1951643D01*
Y1951476D01*
X825321Y1951393D01*
G01X831561Y1946726D02*
Y1950059D01*
G01Y1949476D02*
X831308Y1949809D01*
X830928Y1949976D01*
X830484Y1950059D01*
X830041Y1949893D01*
X829661Y1949559D01*
X829408Y1949059D01*
X829281Y1948393D01*
X829408Y1947726D01*
X829661Y1947226D01*
X830041Y1946893D01*
X830484Y1946726D01*
X830928Y1946809D01*
X831308Y1947059D01*
X831561Y1947393D01*
G01X833621Y1946726D02*
Y1950059D01*
G01Y1949143D02*
X833811Y1949559D01*
X834128Y1949893D01*
X834571Y1950059D01*
X835014Y1949893D01*
X835331Y1949559D01*
X835521Y1949143D01*
Y1946726D01*
G01Y1949143D02*
X835711Y1949559D01*
X836028Y1949893D01*
X836471Y1950059D01*
X836914Y1949893D01*
X837231Y1949559D01*
X837421Y1949059D01*
Y1946726D01*
G01X839671Y1948976D02*
X841698D01*
X841508Y1949559D01*
X841191Y1949893D01*
X840748Y1950059D01*
X840304Y1949976D01*
X839924Y1949726D01*
X839671Y1949143D01*
X839544Y1948643D01*
Y1948143D01*
X839671Y1947643D01*
X839988Y1947143D01*
X840368Y1946809D01*
X840811Y1946726D01*
X841254Y1946893D01*
X841698Y1947393D01*
G01X845721Y1951726D02*
Y1946726D01*
G01X844834Y1950059D02*
X846608D01*
G01X849871Y1948976D02*
X851898D01*
X851708Y1949559D01*
X851391Y1949893D01*
X850948Y1950059D01*
X850504Y1949976D01*
X850124Y1949726D01*
X849871Y1949143D01*
X849744Y1948643D01*
Y1948143D01*
X849871Y1947643D01*
X850188Y1947143D01*
X850568Y1946809D01*
X851011Y1946726D01*
X851454Y1946893D01*
X851898Y1947393D01*
G01X855034Y1946726D02*
Y1950059D01*
G01Y1949393D02*
X855351Y1949726D01*
X855668Y1949976D01*
X856111Y1950059D01*
X856428Y1949976D01*
X856808Y1949726D01*
G01X866121Y1946726D02*
Y1951726D01*
X865361Y1950726D01*
G01Y1946726D02*
X866881D01*
G01X869321D02*
Y1950059D01*
G01Y1949143D02*
X869511Y1949559D01*
X869828Y1949893D01*
X870271Y1950059D01*
X870714Y1949893D01*
X871031Y1949559D01*
X871221Y1949143D01*
Y1946726D01*
G01Y1949143D02*
X871411Y1949559D01*
X871728Y1949893D01*
X872171Y1950059D01*
X872614Y1949893D01*
X872931Y1949559D01*
X873121Y1949059D01*
Y1946726D01*
G01X874421D02*
Y1950059D01*
G01Y1949143D02*
X874611Y1949559D01*
X874928Y1949893D01*
X875371Y1950059D01*
X875814Y1949893D01*
X876131Y1949559D01*
X876321Y1949143D01*
Y1946726D01*
G01Y1949143D02*
X876511Y1949559D01*
X876828Y1949893D01*
X877271Y1950059D01*
X877714Y1949893D01*
X878031Y1949559D01*
X878221Y1949059D01*
Y1946726D01*
G01X887914Y1951309D02*
X887534Y1951559D01*
X887091Y1951726D01*
X886584D01*
X886014Y1951476D01*
X885571Y1951059D01*
X885254Y1950559D01*
X885001Y1949726D01*
X884938Y1948976D01*
X885064Y1948226D01*
X885254Y1947726D01*
X885634Y1947226D01*
X886078Y1946893D01*
X886521Y1946726D01*
X886964D01*
X887408Y1946893D01*
X887788Y1947143D01*
X888104Y1947476D01*
G01X891621Y1946726D02*
X891241Y1946809D01*
X890861Y1947143D01*
X890608Y1947726D01*
X890481Y1948393D01*
X890608Y1949059D01*
X890861Y1949643D01*
X891241Y1949976D01*
X891621Y1950059D01*
X892001Y1949976D01*
X892381Y1949643D01*
X892634Y1949059D01*
X892698Y1948393D01*
X892634Y1947726D01*
X892381Y1947143D01*
X892001Y1946809D01*
X891621Y1946726D01*
G01X895581Y1945059D02*
Y1950059D01*
G01Y1949309D02*
X895898Y1949726D01*
X896214Y1949976D01*
X896721Y1950059D01*
X897164Y1949976D01*
X897608Y1949559D01*
X897798Y1948976D01*
X897861Y1948393D01*
X897798Y1947809D01*
X897608Y1947226D01*
X897228Y1946893D01*
X896721Y1946726D01*
X896278Y1946809D01*
X895834Y1947059D01*
X895581Y1947393D01*
G01X900681Y1945059D02*
Y1950059D01*
G01Y1949309D02*
X900998Y1949726D01*
X901314Y1949976D01*
X901821Y1950059D01*
X902264Y1949976D01*
X902708Y1949559D01*
X902898Y1948976D01*
X902961Y1948393D01*
X902898Y1947809D01*
X902708Y1947226D01*
X902328Y1946893D01*
X901821Y1946726D01*
X901378Y1946809D01*
X900934Y1947059D01*
X900681Y1947393D01*
G01X905971Y1948976D02*
X907998D01*
X907808Y1949559D01*
X907491Y1949893D01*
X907048Y1950059D01*
X906604Y1949976D01*
X906224Y1949726D01*
X905971Y1949143D01*
X905844Y1948643D01*
Y1948143D01*
X905971Y1947643D01*
X906288Y1947143D01*
X906668Y1946809D01*
X907111Y1946726D01*
X907554Y1946893D01*
X907998Y1947393D01*
G01X911134Y1946726D02*
Y1950059D01*
G01Y1949393D02*
X911451Y1949726D01*
X911768Y1949976D01*
X912211Y1950059D01*
X912528Y1949976D01*
X912908Y1949726D01*
G01X815909Y2008418D02*
Y2003418D01*
G01X814452Y2008418D02*
X817366D01*
G01X821009Y2003418D02*
X820629Y2003501D01*
X820249Y2003835D01*
X819996Y2004418D01*
X819869Y2005085D01*
X819996Y2005751D01*
X820249Y2006335D01*
X820629Y2006668D01*
X821009Y2006751D01*
X821389Y2006668D01*
X821769Y2006335D01*
X822022Y2005751D01*
X822086Y2005085D01*
X822022Y2004418D01*
X821769Y2003835D01*
X821389Y2003501D01*
X821009Y2003418D01*
G01X826109D02*
Y2008418D01*
G01X830259Y2005668D02*
X832286D01*
X832096Y2006251D01*
X831779Y2006585D01*
X831336Y2006751D01*
X830892Y2006668D01*
X830512Y2006418D01*
X830259Y2005835D01*
X830132Y2005335D01*
Y2004835D01*
X830259Y2004335D01*
X830576Y2003835D01*
X830956Y2003501D01*
X831399Y2003418D01*
X831842Y2003585D01*
X832286Y2004085D01*
G01X835422Y2003418D02*
Y2006751D01*
G01Y2006085D02*
X835739Y2006418D01*
X836056Y2006668D01*
X836499Y2006751D01*
X836816Y2006668D01*
X837196Y2006418D01*
G01X842549Y2003418D02*
Y2006751D01*
G01Y2006168D02*
X842296Y2006501D01*
X841916Y2006668D01*
X841472Y2006751D01*
X841029Y2006585D01*
X840649Y2006251D01*
X840396Y2005751D01*
X840269Y2005085D01*
X840396Y2004418D01*
X840649Y2003918D01*
X841029Y2003585D01*
X841472Y2003418D01*
X841916Y2003501D01*
X842296Y2003751D01*
X842549Y2004085D01*
G01X845432Y2003418D02*
Y2006751D01*
G01Y2005918D02*
X845686Y2006335D01*
X846066Y2006668D01*
X846572Y2006751D01*
X847016Y2006668D01*
X847396Y2006335D01*
X847586Y2005751D01*
Y2003418D01*
G01X852622Y2006335D02*
X852179Y2006668D01*
X851799Y2006751D01*
X851292Y2006585D01*
X850912Y2006251D01*
X850659Y2005668D01*
X850596Y2005085D01*
X850659Y2004501D01*
X850912Y2004001D01*
X851292Y2003585D01*
X851799Y2003418D01*
X852242Y2003585D01*
X852622Y2003918D01*
G01X855759Y2005668D02*
X857786D01*
X857596Y2006251D01*
X857279Y2006585D01*
X856836Y2006751D01*
X856392Y2006668D01*
X856012Y2006418D01*
X855759Y2005835D01*
X855632Y2005335D01*
Y2004835D01*
X855759Y2004335D01*
X856076Y2003835D01*
X856456Y2003501D01*
X856899Y2003418D01*
X857342Y2003585D01*
X857786Y2004085D01*
G01X866212Y2005085D02*
X867732D01*
G01X866909Y2006168D02*
Y2004001D01*
G01X872009Y2008418D02*
X871502Y2008251D01*
X871122Y2007835D01*
X870869Y2007335D01*
X870679Y2006668D01*
X870616Y2005918D01*
X870679Y2005168D01*
X870869Y2004501D01*
X871122Y2004001D01*
X871502Y2003585D01*
X872009Y2003418D01*
X872516Y2003585D01*
X872896Y2004001D01*
X873149Y2004501D01*
X873339Y2005168D01*
X873402Y2005918D01*
X873339Y2006668D01*
X873149Y2007335D01*
X872896Y2007835D01*
X872516Y2008251D01*
X872009Y2008418D01*
G01X877109Y2003251D02*
X876982Y2003335D01*
Y2003501D01*
X877109Y2003585D01*
X877236Y2003501D01*
Y2003335D01*
X877109Y2003251D01*
G01X882209Y2008418D02*
X881702Y2008251D01*
X881322Y2007835D01*
X881069Y2007335D01*
X880879Y2006668D01*
X880816Y2005918D01*
X880879Y2005168D01*
X881069Y2004501D01*
X881322Y2004001D01*
X881702Y2003585D01*
X882209Y2003418D01*
X882716Y2003585D01*
X883096Y2004001D01*
X883349Y2004501D01*
X883539Y2005168D01*
X883602Y2005918D01*
X883539Y2006668D01*
X883349Y2007335D01*
X883096Y2007835D01*
X882716Y2008251D01*
X882209Y2008418D01*
G01X885916Y2004168D02*
X886296Y2003751D01*
X886739Y2003501D01*
X887309Y2003418D01*
X887879Y2003585D01*
X888322Y2003918D01*
X888639Y2004501D01*
X888702Y2005168D01*
X888576Y2005835D01*
X888259Y2006251D01*
X887816Y2006585D01*
X887372Y2006668D01*
X886929Y2006585D01*
X886359Y2006251D01*
X886549Y2008418D01*
X888259D01*
G01X892409D02*
X891902Y2008251D01*
X891522Y2007835D01*
X891269Y2007335D01*
X891079Y2006668D01*
X891016Y2005918D01*
X891079Y2005168D01*
X891269Y2004501D01*
X891522Y2004001D01*
X891902Y2003585D01*
X892409Y2003418D01*
X892916Y2003585D01*
X893296Y2004001D01*
X893549Y2004501D01*
X893739Y2005168D01*
X893802Y2005918D01*
X893739Y2006668D01*
X893549Y2007335D01*
X893296Y2007835D01*
X892916Y2008251D01*
X892409Y2008418D01*
G01X897509Y2003418D02*
X897952Y2003501D01*
X898459Y2003751D01*
X898776Y2004168D01*
X898902Y2004751D01*
X898776Y2005335D01*
X898396Y2005835D01*
X897826Y2006085D01*
X897192D01*
X896812Y2006251D01*
X896496Y2006668D01*
X896369Y2007251D01*
X896559Y2007835D01*
X897002Y2008251D01*
X897509Y2008418D01*
X898016Y2008251D01*
X898459Y2007835D01*
X898649Y2007251D01*
X898522Y2006668D01*
X898206Y2006251D01*
X897826Y2006085D01*
X897192D01*
X896622Y2005835D01*
X896242Y2005335D01*
X896116Y2004751D01*
X896242Y2004168D01*
X896559Y2003751D01*
X897066Y2003501D01*
X897509Y2003418D01*
G01X900709D02*
Y2006751D01*
G01Y2005835D02*
X900899Y2006251D01*
X901216Y2006585D01*
X901659Y2006751D01*
X902102Y2006585D01*
X902419Y2006251D01*
X902609Y2005835D01*
Y2003418D01*
G01Y2005835D02*
X902799Y2006251D01*
X903116Y2006585D01*
X903559Y2006751D01*
X904002Y2006585D01*
X904319Y2006251D01*
X904509Y2005751D01*
Y2003418D01*
G01X905809D02*
Y2006751D01*
G01Y2005835D02*
X905999Y2006251D01*
X906316Y2006585D01*
X906759Y2006751D01*
X907202Y2006585D01*
X907519Y2006251D01*
X907709Y2005835D01*
Y2003418D01*
G01Y2005835D02*
X907899Y2006251D01*
X908216Y2006585D01*
X908659Y2006751D01*
X909102Y2006585D01*
X909419Y2006251D01*
X909609Y2005751D01*
Y2003418D01*
G01X911669Y2003251D02*
X913949Y2008418D01*
G01X917086Y2005085D02*
X918732D01*
G01X923009Y2008418D02*
X922502Y2008251D01*
X922122Y2007835D01*
X921869Y2007335D01*
X921679Y2006668D01*
X921616Y2005918D01*
X921679Y2005168D01*
X921869Y2004501D01*
X922122Y2004001D01*
X922502Y2003585D01*
X923009Y2003418D01*
X923516Y2003585D01*
X923896Y2004001D01*
X924149Y2004501D01*
X924339Y2005168D01*
X924402Y2005918D01*
X924339Y2006668D01*
X924149Y2007335D01*
X923896Y2007835D01*
X923516Y2008251D01*
X923009Y2008418D01*
G01X928109Y2003251D02*
X927982Y2003335D01*
Y2003501D01*
X928109Y2003585D01*
X928236Y2003501D01*
Y2003335D01*
X928109Y2003251D01*
G01X933209Y2008418D02*
X932702Y2008251D01*
X932322Y2007835D01*
X932069Y2007335D01*
X931879Y2006668D01*
X931816Y2005918D01*
X931879Y2005168D01*
X932069Y2004501D01*
X932322Y2004001D01*
X932702Y2003585D01*
X933209Y2003418D01*
X933716Y2003585D01*
X934096Y2004001D01*
X934349Y2004501D01*
X934539Y2005168D01*
X934602Y2005918D01*
X934539Y2006668D01*
X934349Y2007335D01*
X934096Y2007835D01*
X933716Y2008251D01*
X933209Y2008418D01*
G01X937106Y2007585D02*
X937486Y2008085D01*
X937929Y2008335D01*
X938436Y2008418D01*
X939069Y2008251D01*
X939512Y2007835D01*
X939639Y2007335D01*
X939576Y2006835D01*
X939322Y2006418D01*
X938056Y2005585D01*
X937486Y2005001D01*
X937106Y2004168D01*
X936979Y2003418D01*
X939639D01*
G01X942016Y2004168D02*
X942396Y2003751D01*
X942839Y2003501D01*
X943409Y2003418D01*
X943979Y2003585D01*
X944422Y2003918D01*
X944739Y2004501D01*
X944802Y2005168D01*
X944676Y2005835D01*
X944359Y2006251D01*
X943916Y2006585D01*
X943472Y2006668D01*
X943029Y2006585D01*
X942459Y2006251D01*
X942649Y2008418D01*
X944359D01*
G01X949269Y2003418D02*
Y2008418D01*
X946926Y2004835D01*
X950092D01*
G01X951709Y2003418D02*
Y2006751D01*
G01Y2005835D02*
X951899Y2006251D01*
X952216Y2006585D01*
X952659Y2006751D01*
X953102Y2006585D01*
X953419Y2006251D01*
X953609Y2005835D01*
Y2003418D01*
G01Y2005835D02*
X953799Y2006251D01*
X954116Y2006585D01*
X954559Y2006751D01*
X955002Y2006585D01*
X955319Y2006251D01*
X955509Y2005751D01*
Y2003418D01*
G01X956809D02*
Y2006751D01*
G01Y2005835D02*
X956999Y2006251D01*
X957316Y2006585D01*
X957759Y2006751D01*
X958202Y2006585D01*
X958519Y2006251D01*
X958709Y2005835D01*
Y2003418D01*
G01Y2005835D02*
X958899Y2006251D01*
X959216Y2006585D01*
X959659Y2006751D01*
X960102Y2006585D01*
X960419Y2006251D01*
X960609Y2005751D01*
Y2003418D01*
G01X744509Y2021018D02*
Y2016018D01*
G01X743052Y2021018D02*
X745966D01*
G01X749609Y2016018D02*
X749229Y2016101D01*
X748849Y2016435D01*
X748596Y2017018D01*
X748469Y2017685D01*
X748596Y2018351D01*
X748849Y2018935D01*
X749229Y2019268D01*
X749609Y2019351D01*
X749989Y2019268D01*
X750369Y2018935D01*
X750622Y2018351D01*
X750686Y2017685D01*
X750622Y2017018D01*
X750369Y2016435D01*
X749989Y2016101D01*
X749609Y2016018D01*
G01X754709D02*
X754329Y2016101D01*
X753949Y2016435D01*
X753696Y2017018D01*
X753569Y2017685D01*
X753696Y2018351D01*
X753949Y2018935D01*
X754329Y2019268D01*
X754709Y2019351D01*
X755089Y2019268D01*
X755469Y2018935D01*
X755722Y2018351D01*
X755786Y2017685D01*
X755722Y2017018D01*
X755469Y2016435D01*
X755089Y2016101D01*
X754709Y2016018D01*
G01X759809D02*
Y2021018D01*
G01X764909Y2019351D02*
Y2016018D01*
G01Y2020685D02*
X764782Y2020768D01*
Y2020935D01*
X764909Y2021018D01*
X765036Y2020935D01*
Y2020768D01*
X764909Y2020685D01*
G01X768932Y2016018D02*
Y2019351D01*
G01Y2018518D02*
X769186Y2018935D01*
X769566Y2019268D01*
X770072Y2019351D01*
X770516Y2019268D01*
X770896Y2018935D01*
X771086Y2018351D01*
Y2016018D01*
G01X774222Y2014768D02*
X774666Y2014435D01*
X775172Y2014351D01*
X775616Y2014435D01*
X775996Y2014851D01*
X776249Y2015435D01*
Y2019351D01*
G01Y2018685D02*
X775996Y2019018D01*
X775616Y2019268D01*
X775172Y2019351D01*
X774666Y2019185D01*
X774349Y2018851D01*
X774096Y2018268D01*
X773969Y2017685D01*
X774032Y2017185D01*
X774286Y2016601D01*
X774666Y2016185D01*
X775172Y2016018D01*
X775552Y2016101D01*
X775996Y2016435D01*
X776249Y2016768D01*
G01X783979Y2016018D02*
Y2021018D01*
G01X786639D02*
Y2016018D01*
G01Y2018518D02*
X783979D01*
G01X790409Y2016018D02*
X790029Y2016101D01*
X789649Y2016435D01*
X789396Y2017018D01*
X789269Y2017685D01*
X789396Y2018351D01*
X789649Y2018935D01*
X790029Y2019268D01*
X790409Y2019351D01*
X790789Y2019268D01*
X791169Y2018935D01*
X791422Y2018351D01*
X791486Y2017685D01*
X791422Y2017018D01*
X791169Y2016435D01*
X790789Y2016101D01*
X790409Y2016018D01*
G01X795509D02*
Y2021018D01*
G01X799659Y2018268D02*
X801686D01*
X801496Y2018851D01*
X801179Y2019185D01*
X800736Y2019351D01*
X800292Y2019268D01*
X799912Y2019018D01*
X799659Y2018435D01*
X799532Y2017935D01*
Y2017435D01*
X799659Y2016935D01*
X799976Y2016435D01*
X800356Y2016101D01*
X800799Y2016018D01*
X801242Y2016185D01*
X801686Y2016685D01*
G01X805709Y2015851D02*
X805582Y2015935D01*
Y2016101D01*
X805709Y2016185D01*
X805836Y2016101D01*
Y2015935D01*
X805709Y2015851D01*
G01Y2018101D02*
X805582Y2018185D01*
Y2018351D01*
X805709Y2018435D01*
X805836Y2018351D01*
Y2018185D01*
X805709Y2018101D01*
G01X814516Y2016018D02*
Y2021018D01*
X815782D01*
X816289Y2020768D01*
X816669Y2020435D01*
X816986Y2019935D01*
X817239Y2019351D01*
X817302Y2018518D01*
X817239Y2017685D01*
X816986Y2017101D01*
X816669Y2016601D01*
X816289Y2016268D01*
X815782Y2016018D01*
X814516D01*
G01X821009Y2019351D02*
Y2016018D01*
G01Y2020685D02*
X820882Y2020768D01*
Y2020935D01*
X821009Y2021018D01*
X821136Y2020935D01*
Y2020768D01*
X821009Y2020685D01*
G01X827249Y2016018D02*
Y2019351D01*
G01Y2018768D02*
X826996Y2019101D01*
X826616Y2019268D01*
X826172Y2019351D01*
X825729Y2019185D01*
X825349Y2018851D01*
X825096Y2018351D01*
X824969Y2017685D01*
X825096Y2017018D01*
X825349Y2016518D01*
X825729Y2016185D01*
X826172Y2016018D01*
X826616Y2016101D01*
X826996Y2016351D01*
X827249Y2016685D01*
G01X829309Y2016018D02*
Y2019351D01*
G01Y2018435D02*
X829499Y2018851D01*
X829816Y2019185D01*
X830259Y2019351D01*
X830702Y2019185D01*
X831019Y2018851D01*
X831209Y2018435D01*
Y2016018D01*
G01Y2018435D02*
X831399Y2018851D01*
X831716Y2019185D01*
X832159Y2019351D01*
X832602Y2019185D01*
X832919Y2018851D01*
X833109Y2018351D01*
Y2016018D01*
G01X835359Y2018268D02*
X837386D01*
X837196Y2018851D01*
X836879Y2019185D01*
X836436Y2019351D01*
X835992Y2019268D01*
X835612Y2019018D01*
X835359Y2018435D01*
X835232Y2017935D01*
Y2017435D01*
X835359Y2016935D01*
X835676Y2016435D01*
X836056Y2016101D01*
X836499Y2016018D01*
X836942Y2016185D01*
X837386Y2016685D01*
G01X841409Y2021018D02*
Y2016018D01*
G01X840522Y2019351D02*
X842296D01*
G01X845559Y2018268D02*
X847586D01*
X847396Y2018851D01*
X847079Y2019185D01*
X846636Y2019351D01*
X846192Y2019268D01*
X845812Y2019018D01*
X845559Y2018435D01*
X845432Y2017935D01*
Y2017435D01*
X845559Y2016935D01*
X845876Y2016435D01*
X846256Y2016101D01*
X846699Y2016018D01*
X847142Y2016185D01*
X847586Y2016685D01*
G01X850722Y2016018D02*
Y2019351D01*
G01Y2018685D02*
X851039Y2019018D01*
X851356Y2019268D01*
X851799Y2019351D01*
X852116Y2019268D01*
X852496Y2019018D01*
G01X862569Y2016018D02*
Y2021018D01*
X860226Y2017435D01*
X863392D01*
G01X865009Y2016018D02*
Y2019351D01*
G01Y2018435D02*
X865199Y2018851D01*
X865516Y2019185D01*
X865959Y2019351D01*
X866402Y2019185D01*
X866719Y2018851D01*
X866909Y2018435D01*
Y2016018D01*
G01Y2018435D02*
X867099Y2018851D01*
X867416Y2019185D01*
X867859Y2019351D01*
X868302Y2019185D01*
X868619Y2018851D01*
X868809Y2018351D01*
Y2016018D01*
G01X870109D02*
Y2019351D01*
G01Y2018435D02*
X870299Y2018851D01*
X870616Y2019185D01*
X871059Y2019351D01*
X871502Y2019185D01*
X871819Y2018851D01*
X872009Y2018435D01*
Y2016018D01*
G01Y2018435D02*
X872199Y2018851D01*
X872516Y2019185D01*
X872959Y2019351D01*
X873402Y2019185D01*
X873719Y2018851D01*
X873909Y2018351D01*
Y2016018D01*
G01X880752D02*
Y2021018D01*
X883666Y2016018D01*
Y2021018D01*
G01X886042Y2016018D02*
Y2021018D01*
X887562D01*
X888069Y2020768D01*
X888449Y2020185D01*
X888576Y2019518D01*
X888449Y2018851D01*
X888132Y2018351D01*
X887562Y2018101D01*
X886042D01*
G01X892409Y2021018D02*
Y2016018D01*
G01X890952Y2021018D02*
X893866D01*
G01X896179Y2016018D02*
Y2021018D01*
G01X898839D02*
Y2016018D01*
G01Y2018518D02*
X896179D01*
G01X763265Y1805366D02*
X762765Y1805746D01*
X762515Y1806189D01*
X762432Y1806696D01*
X762599Y1807329D01*
X763015Y1807772D01*
X763515Y1807899D01*
X764015Y1807836D01*
X764432Y1807582D01*
X765265Y1806316D01*
X765849Y1805746D01*
X766682Y1805366D01*
X767432Y1805239D01*
Y1807899D01*
G01X768947Y1816411D02*
X769932Y1810506D01*
X770916Y1816411D01*
X768947D01*
G01X769932Y1806569D02*
Y1810506D01*
G01X770916Y1796726D02*
X769932Y1802632D01*
X768947Y1796726D01*
X770916D01*
G01X769932Y1806569D02*
Y1802632D01*
G01X784499D02*
X769538D01*
G01X784499Y1810506D02*
X769538D01*
G01X771762Y1883246D02*
X785225Y1861705D01*
G01X775727Y1878760D02*
X771762Y1883246D01*
X774058Y1877717D01*
X775727Y1878760D01*
G01X793160Y1783931D02*
X799065Y1784915D01*
X793160Y1785900D01*
Y1783931D01*
G01X784351Y1867821D02*
X788591Y1870471D01*
X787340Y1870585D01*
G01X783948Y1868465D02*
X784754Y1867176D01*
G01X777311Y1885801D02*
X807640Y1892800D01*
G01X782844Y1888088D02*
X777311Y1885801D01*
X783287Y1886170D01*
X782844Y1888088D01*
G01X797049Y1899335D02*
X793864Y1890904D01*
G01X787955Y1873847D02*
X778945Y1874112D01*
G01X785950Y1873980D02*
G03I-2500J0D01*
G01X797957Y1895119D02*
G03I-2501J0D01*
G01X778641Y1983946D02*
X814978Y1992020D01*
G01X784193Y1986187D02*
X778641Y1983946D01*
X784620Y1984267D01*
X784193Y1986187D01*
G01X803972Y1788415D02*
X804352Y1787832D01*
X804858Y1787498D01*
X805428Y1787415D01*
X805935Y1787498D01*
X806442Y1787915D01*
X806758Y1788415D01*
X806822Y1788915D01*
X806695Y1789498D01*
X806252Y1789915D01*
X805808Y1790082D01*
X805238D01*
G01X805808D02*
X806188Y1790332D01*
X806505Y1790748D01*
X806632Y1791248D01*
X806505Y1791748D01*
X806188Y1792165D01*
X805618Y1792415D01*
X805048Y1792332D01*
X804478Y1791998D01*
G01X816782Y1785900D02*
X810876Y1784915D01*
X816782Y1783931D01*
Y1785900D01*
G01X805365Y1784915D02*
X810876D01*
G01X805365D02*
X799065D01*
G01X810876Y1804207D02*
Y1784522D01*
G01X799065Y1804207D02*
Y1784522D01*
G01X799990Y1894626D02*
X800491Y1894143D01*
X801060Y1893932D01*
X801634Y1893979D01*
X802109Y1894175D01*
X802509Y1894694D01*
X802705Y1895253D01*
X802654Y1895754D01*
X802400Y1896294D01*
X801874Y1896600D01*
X801405Y1896663D01*
X800849Y1896535D01*
G01X801405Y1896663D02*
X801719Y1896992D01*
X801934Y1897469D01*
X801945Y1897985D01*
X801709Y1898444D01*
X801307Y1898779D01*
X800695Y1898894D01*
X800158Y1898685D01*
X799678Y1898232D01*
G01X809663Y1993400D02*
X808578Y1998281D01*
X807068Y1994275D01*
X810159Y1994962D01*
G01X804441Y1998642D02*
X801187Y1990236D01*
G01X805314Y1994439D02*
G03I-2500J0D01*
G01X-723776Y2987387D02*
Y-376795D01*
Y-489221D01*
X1782976D01*
Y-376795D01*
Y2987387D01*
X-723776D01*
G01X-69662Y2116817D02*
X-69114Y2116922D01*
X-68487Y2117237D01*
X-68095Y2117762D01*
X-67939Y2118497D01*
X-68095Y2119232D01*
X-68565Y2119862D01*
X-69270Y2120177D01*
X-70054D01*
X-70524Y2120387D01*
X-70915Y2120912D01*
X-71072Y2121647D01*
X-70837Y2122382D01*
X-70289Y2122907D01*
X-69662Y2123117D01*
X-69035Y2122907D01*
X-68487Y2122382D01*
X-68252Y2121647D01*
X-68409Y2120912D01*
X-68800Y2120387D01*
X-69270Y2120177D01*
X-70054D01*
X-70759Y2119862D01*
X-71229Y2119232D01*
X-71385Y2118497D01*
X-71229Y2117762D01*
X-70837Y2117237D01*
X-70210Y2116922D01*
X-69662Y2116817D01*
G01X-63362D02*
Y2123117D01*
X-64302Y2121857D01*
G01Y2116817D02*
X-62422D01*
G01X-57062D02*
X-56514Y2116922D01*
X-55887Y2117237D01*
X-55495Y2117762D01*
X-55339Y2118497D01*
X-55495Y2119232D01*
X-55965Y2119862D01*
X-56670Y2120177D01*
X-57454D01*
X-57924Y2120387D01*
X-58315Y2120912D01*
X-58472Y2121647D01*
X-58237Y2122382D01*
X-57689Y2122907D01*
X-57062Y2123117D01*
X-56435Y2122907D01*
X-55887Y2122382D01*
X-55652Y2121647D01*
X-55809Y2120912D01*
X-56200Y2120387D01*
X-56670Y2120177D01*
X-57454D01*
X-58159Y2119862D01*
X-58629Y2119232D01*
X-58785Y2118497D01*
X-58629Y2117762D01*
X-58237Y2117237D01*
X-57610Y2116922D01*
X-57062Y2116817D01*
G01X-50762D02*
X-50214Y2116922D01*
X-49587Y2117237D01*
X-49195Y2117762D01*
X-49039Y2118497D01*
X-49195Y2119232D01*
X-49665Y2119862D01*
X-50370Y2120177D01*
X-51154D01*
X-51624Y2120387D01*
X-52015Y2120912D01*
X-52172Y2121647D01*
X-51937Y2122382D01*
X-51389Y2122907D01*
X-50762Y2123117D01*
X-50135Y2122907D01*
X-49587Y2122382D01*
X-49352Y2121647D01*
X-49509Y2120912D01*
X-49900Y2120387D01*
X-50370Y2120177D01*
X-51154D01*
X-51859Y2119862D01*
X-52329Y2119232D01*
X-52485Y2118497D01*
X-52329Y2117762D01*
X-51937Y2117237D01*
X-51310Y2116922D01*
X-50762Y2116817D01*
G01X-44462Y2116607D02*
X-44619Y2116712D01*
Y2116922D01*
X-44462Y2117027D01*
X-44305Y2116922D01*
Y2116712D01*
X-44462Y2116607D01*
G01X-39494Y2117552D02*
X-38945Y2117027D01*
X-38319Y2116817D01*
X-37692Y2117027D01*
X-37144Y2117657D01*
X-36752Y2118602D01*
X-36595Y2119547D01*
Y2120702D01*
X-36752Y2121647D01*
X-37144Y2122487D01*
X-37614Y2122907D01*
X-38162Y2123117D01*
X-38789Y2122907D01*
X-39259Y2122487D01*
X-39572Y2121857D01*
X-39729Y2121017D01*
X-39572Y2120282D01*
X-39180Y2119547D01*
X-38710Y2119127D01*
X-38162Y2119022D01*
X-37535Y2119232D01*
X-37065Y2119757D01*
X-36595Y2120702D01*
G01X-31862Y2116817D02*
X-31314Y2116922D01*
X-30687Y2117237D01*
X-30295Y2117762D01*
X-30139Y2118497D01*
X-30295Y2119232D01*
X-30765Y2119862D01*
X-31470Y2120177D01*
X-32254D01*
X-32724Y2120387D01*
X-33115Y2120912D01*
X-33272Y2121647D01*
X-33037Y2122382D01*
X-32489Y2122907D01*
X-31862Y2123117D01*
X-31235Y2122907D01*
X-30687Y2122382D01*
X-30452Y2121647D01*
X-30609Y2120912D01*
X-31000Y2120387D01*
X-31470Y2120177D01*
X-32254D01*
X-32959Y2119862D01*
X-33429Y2119232D01*
X-33585Y2118497D01*
X-33429Y2117762D01*
X-33037Y2117237D01*
X-32410Y2116922D01*
X-31862Y2116817D01*
G01X6705Y-124160D02*
X7332Y-124685D01*
X8037Y-125000D01*
X8663D01*
X9290Y-124685D01*
X9760Y-124160D01*
X9995Y-123425D01*
X9838Y-122690D01*
X9447Y-122060D01*
X8742Y-121640D01*
X7802Y-121430D01*
X7253Y-121010D01*
X7018Y-120275D01*
X7175Y-119540D01*
X7567Y-119015D01*
X8115Y-118700D01*
X8663D01*
X9212Y-118910D01*
X9682Y-119435D01*
G01X13005Y-125000D02*
Y-118700D01*
G01X16295D02*
Y-125000D01*
G01Y-121850D02*
X13005D01*
G01X20010Y-118700D02*
X21890D01*
G01X20950D02*
Y-125000D01*
G01X20010D02*
X21890D01*
G01X28817D02*
X25683D01*
Y-118700D01*
X28817D01*
G01X27563Y-121745D02*
X25683D01*
G01X31748Y-125000D02*
Y-118700D01*
X35352Y-125000D01*
Y-118700D01*
G01X39693Y-126155D02*
X40007Y-124790D01*
G01X46150Y-118700D02*
Y-125000D01*
G01X44348Y-118700D02*
X47952D01*
G01X50492Y-125000D02*
X52450Y-118700D01*
X54408Y-125000D01*
G01X53703Y-122795D02*
X51197D01*
G01X57810Y-118700D02*
X59690D01*
G01X58750D02*
Y-125000D01*
G01X57810D02*
X59690D01*
G01X62700Y-118700D02*
X63797Y-125000D01*
X65050Y-118700D01*
X66303Y-125000D01*
X67400Y-118700D01*
G01X69392Y-125000D02*
X71350Y-118700D01*
X73308Y-125000D01*
G01X72603Y-122795D02*
X70097D01*
G01X75848Y-125000D02*
Y-118700D01*
X79452Y-125000D01*
Y-118700D01*
G01X88683Y-125000D02*
Y-118700D01*
X90642D01*
X91268Y-119015D01*
X91660Y-119435D01*
X91817Y-120275D01*
X91660Y-121115D01*
X91190Y-121640D01*
X90642Y-121955D01*
X88683D01*
G01X90642D02*
X91817Y-125000D01*
G01X96550Y-125210D02*
X96393Y-125105D01*
Y-124895D01*
X96550Y-124790D01*
X96707Y-124895D01*
Y-125105D01*
X96550Y-125210D01*
G01X102850Y-125000D02*
X102223Y-124895D01*
X101675Y-124475D01*
X101205Y-123845D01*
X100892Y-123110D01*
X100735Y-122270D01*
Y-121430D01*
X100892Y-120590D01*
X101205Y-119855D01*
X101675Y-119225D01*
X102223Y-118805D01*
X102850Y-118700D01*
X103477Y-118805D01*
X104025Y-119225D01*
X104495Y-119855D01*
X104808Y-120590D01*
X104965Y-121430D01*
Y-122270D01*
X104808Y-123110D01*
X104495Y-123845D01*
X104025Y-124475D01*
X103477Y-124895D01*
X102850Y-125000D01*
G01X109150Y-125210D02*
X108993Y-125105D01*
Y-124895D01*
X109150Y-124790D01*
X109307Y-124895D01*
Y-125105D01*
X109150Y-125210D01*
G01X117173Y-119225D02*
X116703Y-118910D01*
X116155Y-118700D01*
X115528D01*
X114823Y-119015D01*
X114275Y-119540D01*
X113883Y-120170D01*
X113570Y-121220D01*
X113492Y-122165D01*
X113648Y-123110D01*
X113883Y-123740D01*
X114353Y-124370D01*
X114902Y-124790D01*
X115450Y-125000D01*
X115998D01*
X116547Y-124790D01*
X117017Y-124475D01*
X117408Y-124055D01*
G01X121750Y-125210D02*
X121593Y-125105D01*
Y-124895D01*
X121750Y-124790D01*
X121907Y-124895D01*
Y-125105D01*
X121750Y-125210D01*
G01X6627Y-115000D02*
Y-108700D01*
G01X9603D02*
X6627Y-112585D01*
G01X10073Y-115000D02*
X7958Y-110800D01*
G01X12927Y-108700D02*
Y-113215D01*
X13240Y-114160D01*
X13867Y-114790D01*
X14650Y-115000D01*
X15433Y-114790D01*
X16060Y-114160D01*
X16373Y-113215D01*
Y-108700D01*
G01X22517Y-115000D02*
X19383D01*
Y-108700D01*
X22517D01*
G01X21263Y-111745D02*
X19383D01*
G01X26310Y-108700D02*
X28190D01*
G01X27250D02*
Y-115000D01*
G01X26310D02*
X28190D01*
G01X38205Y-114160D02*
X38832Y-114685D01*
X39537Y-115000D01*
X40163D01*
X40790Y-114685D01*
X41260Y-114160D01*
X41495Y-113425D01*
X41338Y-112690D01*
X40947Y-112060D01*
X40242Y-111640D01*
X39302Y-111430D01*
X38753Y-111010D01*
X38518Y-110275D01*
X38675Y-109540D01*
X39067Y-109015D01*
X39615Y-108700D01*
X40163D01*
X40712Y-108910D01*
X41182Y-109435D01*
G01X44505Y-115000D02*
Y-108700D01*
G01X47795D02*
Y-115000D01*
G01Y-111850D02*
X44505D01*
G01X50492Y-115000D02*
X52450Y-108700D01*
X54408Y-115000D01*
G01X53703Y-112795D02*
X51197D01*
G01X56948Y-115000D02*
Y-108700D01*
X60552Y-115000D01*
Y-108700D01*
G01X69705Y-115000D02*
Y-108700D01*
G01X72995D02*
Y-115000D01*
G01Y-111850D02*
X69705D01*
G01X76005Y-114160D02*
X76632Y-114685D01*
X77337Y-115000D01*
X77963D01*
X78590Y-114685D01*
X79060Y-114160D01*
X79295Y-113425D01*
X79138Y-112690D01*
X78747Y-112060D01*
X78042Y-111640D01*
X77102Y-111430D01*
X76553Y-111010D01*
X76318Y-110275D01*
X76475Y-109540D01*
X76867Y-109015D01*
X77415Y-108700D01*
X77963D01*
X78512Y-108910D01*
X78982Y-109435D01*
G01X83010Y-108700D02*
X84890D01*
G01X83950D02*
Y-115000D01*
G01X83010D02*
X84890D01*
G01X88292D02*
X90250Y-108700D01*
X92208Y-115000D01*
G01X91503Y-112795D02*
X88997D01*
G01X94748Y-115000D02*
Y-108700D01*
X98352Y-115000D01*
Y-108700D01*
G01X103320Y-111850D02*
X104887D01*
Y-113740D01*
X104417Y-114370D01*
X103868Y-114790D01*
X103085Y-115000D01*
X102302Y-114790D01*
X101753Y-114370D01*
X101283Y-113740D01*
X100970Y-113005D01*
X100813Y-112165D01*
Y-111430D01*
X100970Y-110800D01*
X101283Y-110065D01*
X101753Y-109435D01*
X102223Y-109015D01*
X102850Y-108700D01*
X103398D01*
X104025Y-108910D01*
X104495Y-109330D01*
G01X108993Y-116155D02*
X109307Y-114790D01*
G01X115450Y-108700D02*
Y-115000D01*
G01X113648Y-108700D02*
X117252D01*
G01X119792Y-115000D02*
X121750Y-108700D01*
X123708Y-115000D01*
G01X123003Y-112795D02*
X120497D01*
G01X128050Y-115000D02*
X127423Y-114895D01*
X126875Y-114475D01*
X126405Y-113845D01*
X126092Y-113110D01*
X125935Y-112270D01*
Y-111430D01*
X126092Y-110590D01*
X126405Y-109855D01*
X126875Y-109225D01*
X127423Y-108805D01*
X128050Y-108700D01*
X128677Y-108805D01*
X129225Y-109225D01*
X129695Y-109855D01*
X130008Y-110590D01*
X130165Y-111430D01*
Y-112270D01*
X130008Y-113110D01*
X129695Y-113845D01*
X129225Y-114475D01*
X128677Y-114895D01*
X128050Y-115000D01*
G01X140650D02*
Y-112165D01*
X139083Y-108700D01*
G01X142217D02*
X140650Y-112165D01*
G01X145227Y-108700D02*
Y-113215D01*
X145540Y-114160D01*
X146167Y-114790D01*
X146950Y-115000D01*
X147733Y-114790D01*
X148360Y-114160D01*
X148673Y-113215D01*
Y-108700D01*
G01X151292Y-115000D02*
X153250Y-108700D01*
X155208Y-115000D01*
G01X154503Y-112795D02*
X151997D01*
G01X157748Y-115000D02*
Y-108700D01*
X161352Y-115000D01*
Y-108700D01*
G01X30650Y-92300D02*
X28130Y-91883D01*
X25925Y-90217D01*
X24035Y-87717D01*
X22775Y-84800D01*
X22145Y-81467D01*
Y-78133D01*
X22775Y-74800D01*
X24035Y-71883D01*
X25925Y-69384D01*
X28130Y-67717D01*
X30650Y-67300D01*
X33170Y-67717D01*
X35375Y-69384D01*
X37265Y-71883D01*
X38525Y-74800D01*
X39155Y-78133D01*
Y-81467D01*
X38525Y-84800D01*
X37265Y-87717D01*
X35375Y-90217D01*
X33170Y-91883D01*
X30650Y-92300D01*
G01X33170Y-85633D02*
X36950Y-92300D01*
G01X50495Y-75634D02*
Y-87300D01*
X51755Y-90217D01*
X53645Y-91883D01*
X55850Y-92300D01*
X58055Y-91883D01*
X59945Y-90217D01*
X61205Y-87300D01*
G01Y-92300D02*
Y-75634D01*
G01X86720Y-92300D02*
Y-75634D01*
G01Y-78550D02*
X85460Y-76884D01*
X83570Y-76050D01*
X81365Y-75634D01*
X79160Y-76467D01*
X77270Y-78133D01*
X76010Y-80634D01*
X75380Y-83967D01*
X76010Y-87300D01*
X77270Y-89801D01*
X79160Y-91467D01*
X81365Y-92300D01*
X83570Y-91883D01*
X85460Y-90634D01*
X86720Y-88967D01*
G01X100895Y-92300D02*
Y-75634D01*
G01Y-79800D02*
X102155Y-77717D01*
X104045Y-76050D01*
X106565Y-75634D01*
X108770Y-76050D01*
X110660Y-77717D01*
X111605Y-80634D01*
Y-92300D01*
G01X131450Y-67300D02*
Y-92300D01*
G01X127040Y-75634D02*
X135860D01*
G01X162320Y-92300D02*
Y-75634D01*
G01Y-78550D02*
X161060Y-76884D01*
X159170Y-76050D01*
X156965Y-75634D01*
X154760Y-76467D01*
X152870Y-78133D01*
X151610Y-80634D01*
X150980Y-83967D01*
X151610Y-87300D01*
X152870Y-89801D01*
X154760Y-91467D01*
X156965Y-92300D01*
X159170Y-91883D01*
X161060Y-90634D01*
X162320Y-88967D01*
G01X6548Y-105000D02*
Y-98700D01*
X10152Y-105000D01*
Y-98700D01*
G01X14650Y-105000D02*
X14023Y-104895D01*
X13475Y-104475D01*
X13005Y-103845D01*
X12692Y-103110D01*
X12535Y-102270D01*
Y-101430D01*
X12692Y-100590D01*
X13005Y-99855D01*
X13475Y-99225D01*
X14023Y-98805D01*
X14650Y-98700D01*
X15277Y-98805D01*
X15825Y-99225D01*
X16295Y-99855D01*
X16608Y-100590D01*
X16765Y-101430D01*
Y-102270D01*
X16608Y-103110D01*
X16295Y-103845D01*
X15825Y-104475D01*
X15277Y-104895D01*
X14650Y-105000D01*
G01X20950Y-105210D02*
X20793Y-105105D01*
Y-104895D01*
X20950Y-104790D01*
X21107Y-104895D01*
Y-105105D01*
X20950Y-105210D01*
G01X27250Y-105000D02*
Y-98700D01*
X26310Y-99960D01*
G01Y-105000D02*
X28190D01*
G01X33550D02*
X34098Y-104895D01*
X34725Y-104580D01*
X35117Y-104055D01*
X35273Y-103320D01*
X35117Y-102585D01*
X34647Y-101955D01*
X33942Y-101640D01*
X33158D01*
X32688Y-101430D01*
X32297Y-100905D01*
X32140Y-100170D01*
X32375Y-99435D01*
X32923Y-98910D01*
X33550Y-98700D01*
X34177Y-98910D01*
X34725Y-99435D01*
X34960Y-100170D01*
X34803Y-100905D01*
X34412Y-101430D01*
X33942Y-101640D01*
X33158D01*
X32453Y-101955D01*
X31983Y-102585D01*
X31827Y-103320D01*
X31983Y-104055D01*
X32375Y-104580D01*
X33002Y-104895D01*
X33550Y-105000D01*
G01X39850D02*
X40398Y-104895D01*
X41025Y-104580D01*
X41417Y-104055D01*
X41573Y-103320D01*
X41417Y-102585D01*
X40947Y-101955D01*
X40242Y-101640D01*
X39458D01*
X38988Y-101430D01*
X38597Y-100905D01*
X38440Y-100170D01*
X38675Y-99435D01*
X39223Y-98910D01*
X39850Y-98700D01*
X40477Y-98910D01*
X41025Y-99435D01*
X41260Y-100170D01*
X41103Y-100905D01*
X40712Y-101430D01*
X40242Y-101640D01*
X39458D01*
X38753Y-101955D01*
X38283Y-102585D01*
X38127Y-103320D01*
X38283Y-104055D01*
X38675Y-104580D01*
X39302Y-104895D01*
X39850Y-105000D01*
G01X45993Y-106155D02*
X46307Y-104790D01*
G01X50100Y-98700D02*
X51197Y-105000D01*
X52450Y-98700D01*
X53703Y-105000D01*
X54800Y-98700D01*
G01X60317Y-105000D02*
X57183D01*
Y-98700D01*
X60317D01*
G01X59063Y-101745D02*
X57183D01*
G01X63248Y-105000D02*
Y-98700D01*
X66852Y-105000D01*
Y-98700D01*
G01X76005Y-105000D02*
Y-98700D01*
G01X79295D02*
Y-105000D01*
G01Y-101850D02*
X76005D01*
G01X81600Y-98700D02*
X82697Y-105000D01*
X83950Y-98700D01*
X85203Y-105000D01*
X86300Y-98700D01*
G01X88292Y-105000D02*
X90250Y-98700D01*
X92208Y-105000D01*
G01X91503Y-102795D02*
X88997D01*
G01X101362Y-99750D02*
X101832Y-99120D01*
X102380Y-98805D01*
X103007Y-98700D01*
X103790Y-98910D01*
X104338Y-99435D01*
X104495Y-100065D01*
X104417Y-100695D01*
X104103Y-101220D01*
X102537Y-102270D01*
X101832Y-103005D01*
X101362Y-104055D01*
X101205Y-105000D01*
X104495D01*
G01X107348D02*
Y-98700D01*
X110952Y-105000D01*
Y-98700D01*
G01X113727Y-105000D02*
Y-98700D01*
X115293D01*
X115920Y-99015D01*
X116390Y-99435D01*
X116782Y-100065D01*
X117095Y-100800D01*
X117173Y-101850D01*
X117095Y-102900D01*
X116782Y-103635D01*
X116390Y-104265D01*
X115920Y-104685D01*
X115293Y-105000D01*
X113727D01*
G01X126483D02*
Y-98700D01*
X128442D01*
X129068Y-99015D01*
X129460Y-99435D01*
X129617Y-100275D01*
X129460Y-101115D01*
X128990Y-101640D01*
X128442Y-101955D01*
X126483D01*
G01X128442D02*
X129617Y-105000D01*
G01X132627D02*
Y-98700D01*
X134193D01*
X134820Y-99015D01*
X135290Y-99435D01*
X135682Y-100065D01*
X135995Y-100800D01*
X136073Y-101850D01*
X135995Y-102900D01*
X135682Y-103635D01*
X135290Y-104265D01*
X134820Y-104685D01*
X134193Y-105000D01*
X132627D01*
G01X140650Y-105210D02*
X140493Y-105105D01*
Y-104895D01*
X140650Y-104790D01*
X140807Y-104895D01*
Y-105105D01*
X140650Y-105210D01*
G01X202000Y-72000D02*
Y-80000D01*
X206000D01*
G01X213800D02*
Y-74667D01*
G01Y-75600D02*
X213400Y-75067D01*
X212800Y-74800D01*
X212100Y-74667D01*
X211400Y-74933D01*
X210800Y-75467D01*
X210400Y-76267D01*
X210200Y-77333D01*
X210400Y-78400D01*
X210800Y-79200D01*
X211400Y-79733D01*
X212100Y-80000D01*
X212800Y-79867D01*
X213400Y-79467D01*
X213800Y-78934D01*
G01X217900Y-82400D02*
X218500Y-82667D01*
X219300Y-82400D01*
X219800Y-81867D01*
X220200Y-81200D01*
X220800Y-79067D01*
X222100Y-74667D01*
G01X218900D02*
X220800Y-79067D01*
G01X226500Y-76400D02*
X229700D01*
X229400Y-75467D01*
X228900Y-74933D01*
X228200Y-74667D01*
X227500Y-74800D01*
X226900Y-75200D01*
X226500Y-76133D01*
X226300Y-76934D01*
Y-77733D01*
X226500Y-78533D01*
X227000Y-79333D01*
X227600Y-79867D01*
X228300Y-80000D01*
X229000Y-79733D01*
X229700Y-78934D01*
G01X234600Y-80000D02*
Y-74667D01*
G01Y-75733D02*
X235100Y-75200D01*
X235600Y-74800D01*
X236300Y-74667D01*
X236800Y-74800D01*
X237400Y-75200D01*
G01X223400Y-128934D02*
X224200Y-129600D01*
X225100Y-130000D01*
X225900D01*
X226700Y-129600D01*
X227300Y-128934D01*
X227600Y-128000D01*
X227400Y-127067D01*
X226900Y-126267D01*
X226000Y-125733D01*
X224800Y-125467D01*
X224100Y-124933D01*
X223800Y-124000D01*
X224000Y-123067D01*
X224500Y-122400D01*
X225200Y-122000D01*
X225900D01*
X226600Y-122267D01*
X227200Y-122933D01*
G01X235300Y-130000D02*
Y-124667D01*
G01Y-125600D02*
X234900Y-125067D01*
X234300Y-124800D01*
X233600Y-124667D01*
X232900Y-124933D01*
X232300Y-125467D01*
X231900Y-126267D01*
X231700Y-127333D01*
X231900Y-128400D01*
X232300Y-129200D01*
X232900Y-129733D01*
X233600Y-130000D01*
X234300Y-129867D01*
X234900Y-129467D01*
X235300Y-128934D01*
G01X239800Y-130000D02*
Y-124667D01*
G01Y-126000D02*
X240200Y-125333D01*
X240800Y-124800D01*
X241600Y-124667D01*
X242300Y-124800D01*
X242900Y-125333D01*
X243200Y-126267D01*
Y-130000D01*
G01X251300Y-122000D02*
Y-130000D01*
G01Y-128800D02*
X250900Y-129467D01*
X250300Y-129867D01*
X249600Y-130000D01*
X248800Y-129733D01*
X248200Y-129067D01*
X247800Y-128267D01*
X247700Y-127333D01*
X247800Y-126400D01*
X248200Y-125600D01*
X248800Y-124933D01*
X249600Y-124667D01*
X250300Y-124800D01*
X250800Y-125067D01*
X251300Y-125600D01*
G01X255400Y-132400D02*
X256000Y-132667D01*
X256800Y-132400D01*
X257300Y-131867D01*
X257700Y-131200D01*
X258300Y-129067D01*
X259600Y-124667D01*
G01X256400D02*
X258300Y-129067D01*
G01X221000Y-105000D02*
Y-97000D01*
X223400D01*
X224200Y-97400D01*
X224800Y-98333D01*
X225000Y-99400D01*
X224800Y-100467D01*
X224300Y-101267D01*
X223400Y-101667D01*
X221000D01*
G01X228500Y-105000D02*
X231000Y-97000D01*
X233500Y-105000D01*
G01X232600Y-102200D02*
X229400D01*
G01X236700Y-105000D02*
Y-97000D01*
X241300Y-105000D01*
Y-97000D01*
G01X249000Y-105000D02*
X245000D01*
Y-97000D01*
X249000D01*
G01X247400Y-100867D02*
X245000D01*
G01X253000Y-97000D02*
Y-105000D01*
X257000D01*
G01X328600Y-123333D02*
X329200Y-122533D01*
X329900Y-122133D01*
X330700Y-122000D01*
X331700Y-122267D01*
X332400Y-122933D01*
X332600Y-123733D01*
X332500Y-124534D01*
X332100Y-125200D01*
X330100Y-126533D01*
X329200Y-127467D01*
X328600Y-128800D01*
X328400Y-130000D01*
X332600D01*
G01X338500Y-122000D02*
X337700Y-122267D01*
X337100Y-122933D01*
X336700Y-123733D01*
X336400Y-124800D01*
X336300Y-126000D01*
X336400Y-127200D01*
X336700Y-128267D01*
X337100Y-129067D01*
X337700Y-129733D01*
X338500Y-130000D01*
X339300Y-129733D01*
X339900Y-129067D01*
X340300Y-128267D01*
X340600Y-127200D01*
X340700Y-126000D01*
X340600Y-124800D01*
X340300Y-123733D01*
X339900Y-122933D01*
X339300Y-122267D01*
X338500Y-122000D01*
G01X346500Y-130000D02*
Y-122000D01*
X345300Y-123600D01*
G01Y-130000D02*
X347700D01*
G01X352600Y-123333D02*
X353200Y-122533D01*
X353900Y-122133D01*
X354700Y-122000D01*
X355700Y-122267D01*
X356400Y-122933D01*
X356600Y-123733D01*
X356500Y-124534D01*
X356100Y-125200D01*
X354100Y-126533D01*
X353200Y-127467D01*
X352600Y-128800D01*
X352400Y-130000D01*
X356600D01*
G01X360700Y-130267D02*
X364300Y-122000D01*
G01X370500D02*
X369700Y-122267D01*
X369100Y-122933D01*
X368700Y-123733D01*
X368400Y-124800D01*
X368300Y-126000D01*
X368400Y-127200D01*
X368700Y-128267D01*
X369100Y-129067D01*
X369700Y-129733D01*
X370500Y-130000D01*
X371300Y-129733D01*
X371900Y-129067D01*
X372300Y-128267D01*
X372600Y-127200D01*
X372700Y-126000D01*
X372600Y-124800D01*
X372300Y-123733D01*
X371900Y-122933D01*
X371300Y-122267D01*
X370500Y-122000D01*
G01X376800Y-129067D02*
X377500Y-129733D01*
X378300Y-130000D01*
X379100Y-129733D01*
X379800Y-128934D01*
X380300Y-127733D01*
X380500Y-126533D01*
Y-125067D01*
X380300Y-123867D01*
X379800Y-122800D01*
X379200Y-122267D01*
X378500Y-122000D01*
X377700Y-122267D01*
X377100Y-122800D01*
X376700Y-123600D01*
X376500Y-124667D01*
X376700Y-125600D01*
X377200Y-126533D01*
X377800Y-127067D01*
X378500Y-127200D01*
X379300Y-126934D01*
X379900Y-126267D01*
X380500Y-125067D01*
G01X384700Y-130267D02*
X388300Y-122000D01*
G01X392600Y-123333D02*
X393200Y-122533D01*
X393900Y-122133D01*
X394700Y-122000D01*
X395700Y-122267D01*
X396400Y-122933D01*
X396600Y-123733D01*
X396500Y-124534D01*
X396100Y-125200D01*
X394100Y-126533D01*
X393200Y-127467D01*
X392600Y-128800D01*
X392400Y-130000D01*
X396600D01*
G01X402500D02*
X403200Y-129867D01*
X404000Y-129467D01*
X404500Y-128800D01*
X404700Y-127867D01*
X404500Y-126934D01*
X403900Y-126133D01*
X403000Y-125733D01*
X402000D01*
X401400Y-125467D01*
X400900Y-124800D01*
X400700Y-123867D01*
X401000Y-122933D01*
X401700Y-122267D01*
X402500Y-122000D01*
X403300Y-122267D01*
X404000Y-122933D01*
X404300Y-123867D01*
X404100Y-124800D01*
X403600Y-125467D01*
X403000Y-125733D01*
X402000D01*
X401100Y-126133D01*
X400500Y-126934D01*
X400300Y-127867D01*
X400500Y-128800D01*
X401000Y-129467D01*
X401800Y-129867D01*
X402500Y-130000D01*
G01X328300Y-105000D02*
Y-97000D01*
X330300D01*
X331100Y-97400D01*
X331700Y-97933D01*
X332200Y-98733D01*
X332600Y-99667D01*
X332700Y-101000D01*
X332600Y-102333D01*
X332200Y-103267D01*
X331700Y-104067D01*
X331100Y-104600D01*
X330300Y-105000D01*
X328300D01*
G01X336000D02*
X338500Y-97000D01*
X341000Y-105000D01*
G01X340100Y-102200D02*
X336900D01*
G01X346500Y-97000D02*
X345700Y-97267D01*
X345100Y-97933D01*
X344700Y-98733D01*
X344400Y-99800D01*
X344300Y-101000D01*
X344400Y-102200D01*
X344700Y-103267D01*
X345100Y-104067D01*
X345700Y-104733D01*
X346500Y-105000D01*
X347300Y-104733D01*
X347900Y-104067D01*
X348300Y-103267D01*
X348600Y-102200D01*
X348700Y-101000D01*
X348600Y-99800D01*
X348300Y-98733D01*
X347900Y-97933D01*
X347300Y-97267D01*
X346500Y-97000D01*
G01X354500D02*
Y-105000D01*
G01X352200Y-97000D02*
X356800D01*
G01X360600Y-101667D02*
X361300Y-100733D01*
X361900Y-100200D01*
X362700Y-99933D01*
X363400Y-100200D01*
X363900Y-100733D01*
X364300Y-101533D01*
X364400Y-102467D01*
X364300Y-103267D01*
X363900Y-104067D01*
X363300Y-104733D01*
X362600Y-105000D01*
X361800Y-104733D01*
X361100Y-103934D01*
X360700Y-102733D01*
X360600Y-101400D01*
X360800Y-99667D01*
X361100Y-98733D01*
X361600Y-97800D01*
X362300Y-97133D01*
X363000Y-97000D01*
X363700Y-97267D01*
X364200Y-97933D01*
G01X367900Y-105000D02*
Y-97000D01*
X370500Y-103667D01*
X373100Y-97000D01*
Y-105000D01*
G01X378500Y-97000D02*
Y-105000D01*
G01X376200Y-97000D02*
X380800D01*
G01X387300Y-100733D02*
X387700Y-100333D01*
X388000Y-99667D01*
X388200Y-98733D01*
X388000Y-97933D01*
X387600Y-97400D01*
X386900Y-97000D01*
X384200D01*
Y-105000D01*
X387500D01*
X388200Y-104467D01*
X388600Y-103667D01*
X388800Y-102733D01*
X388600Y-101800D01*
X388000Y-101000D01*
X387300Y-100733D01*
X384200D01*
G01X394500Y-105000D02*
X395200Y-104867D01*
X396000Y-104467D01*
X396500Y-103800D01*
X396700Y-102867D01*
X396500Y-101934D01*
X395900Y-101133D01*
X395000Y-100733D01*
X394000D01*
X393400Y-100467D01*
X392900Y-99800D01*
X392700Y-98867D01*
X393000Y-97933D01*
X393700Y-97267D01*
X394500Y-97000D01*
X395300Y-97267D01*
X396000Y-97933D01*
X396300Y-98867D01*
X396100Y-99800D01*
X395600Y-100467D01*
X395000Y-100733D01*
X394000D01*
X393100Y-101133D01*
X392500Y-101934D01*
X392300Y-102867D01*
X392500Y-103800D01*
X393000Y-104467D01*
X393800Y-104867D01*
X394500Y-105000D01*
G01X400300D02*
Y-97000D01*
X402300D01*
X403100Y-97400D01*
X403700Y-97933D01*
X404200Y-98733D01*
X404600Y-99667D01*
X404700Y-101000D01*
X404600Y-102333D01*
X404200Y-103267D01*
X403700Y-104067D01*
X403100Y-104600D01*
X402300Y-105000D01*
X400300D01*
G01X410500Y-97000D02*
X409700Y-97267D01*
X409100Y-97933D01*
X408700Y-98733D01*
X408400Y-99800D01*
X408300Y-101000D01*
X408400Y-102200D01*
X408700Y-103267D01*
X409100Y-104067D01*
X409700Y-104733D01*
X410500Y-105000D01*
X411300Y-104733D01*
X411900Y-104067D01*
X412300Y-103267D01*
X412600Y-102200D01*
X412700Y-101000D01*
X412600Y-99800D01*
X412300Y-98733D01*
X411900Y-97933D01*
X411300Y-97267D01*
X410500Y-97000D01*
G01X350500Y-72000D02*
Y-80000D01*
G01X348200Y-72000D02*
X352800D01*
G01X356600Y-76667D02*
X357300Y-75733D01*
X357900Y-75200D01*
X358700Y-74933D01*
X359400Y-75200D01*
X359900Y-75733D01*
X360300Y-76533D01*
X360400Y-77467D01*
X360300Y-78267D01*
X359900Y-79067D01*
X359300Y-79733D01*
X358600Y-80000D01*
X357800Y-79733D01*
X357100Y-78934D01*
X356700Y-77733D01*
X356600Y-76400D01*
X356800Y-74667D01*
X357100Y-73733D01*
X357600Y-72800D01*
X358300Y-72133D01*
X359000Y-72000D01*
X359700Y-72267D01*
X360200Y-72933D01*
G01X363900Y-80000D02*
Y-72000D01*
X366500Y-78667D01*
X369100Y-72000D01*
Y-80000D01*
G01X371500Y-82667D02*
X377500D01*
G01X380500Y-80000D02*
Y-72000D01*
X382900D01*
X383700Y-72400D01*
X384300Y-73333D01*
X384500Y-74400D01*
X384300Y-75467D01*
X383800Y-76267D01*
X382900Y-76667D01*
X380500D01*
G01X388300Y-80000D02*
Y-72000D01*
X390300D01*
X391100Y-72400D01*
X391700Y-72933D01*
X392200Y-73733D01*
X392600Y-74667D01*
X392700Y-76000D01*
X392600Y-77333D01*
X392200Y-78267D01*
X391700Y-79067D01*
X391100Y-79600D01*
X390300Y-80000D01*
X388300D01*
G01X399300Y-75733D02*
X399700Y-75333D01*
X400000Y-74667D01*
X400200Y-73733D01*
X400000Y-72933D01*
X399600Y-72400D01*
X398900Y-72000D01*
X396200D01*
Y-80000D01*
X399500D01*
X400200Y-79467D01*
X400600Y-78667D01*
X400800Y-77733D01*
X400600Y-76800D01*
X400000Y-76000D01*
X399300Y-75733D01*
X396200D01*
G01X403500Y-82667D02*
X409500D01*
G01X412300Y-80000D02*
Y-72000D01*
X414300D01*
X415100Y-72400D01*
X415700Y-72933D01*
X416200Y-73733D01*
X416600Y-74667D01*
X416700Y-76000D01*
X416600Y-77333D01*
X416200Y-78267D01*
X415700Y-79067D01*
X415100Y-79600D01*
X414300Y-80000D01*
X412300D01*
G01X419500Y-82667D02*
X425500D01*
G01X431300Y-75733D02*
X431700Y-75333D01*
X432000Y-74667D01*
X432200Y-73733D01*
X432000Y-72933D01*
X431600Y-72400D01*
X430900Y-72000D01*
X428200D01*
Y-80000D01*
X431500D01*
X432200Y-79467D01*
X432600Y-78667D01*
X432800Y-77733D01*
X432600Y-76800D01*
X432000Y-76000D01*
X431300Y-75733D01*
X428200D01*
G01X436300Y-80000D02*
Y-72000D01*
X438300D01*
X439100Y-72400D01*
X439700Y-72933D01*
X440200Y-73733D01*
X440600Y-74667D01*
X440700Y-76000D01*
X440600Y-77333D01*
X440200Y-78267D01*
X439700Y-79067D01*
X439100Y-79600D01*
X438300Y-80000D01*
X436300D01*
G01X443300Y-130000D02*
Y-122000D01*
X445300D01*
X446100Y-122400D01*
X446700Y-122933D01*
X447200Y-123733D01*
X447600Y-124667D01*
X447700Y-126000D01*
X447600Y-127333D01*
X447200Y-128267D01*
X446700Y-129067D01*
X446100Y-129600D01*
X445300Y-130000D01*
X443300D01*
G01X473000D02*
Y-122000D01*
X471800Y-123600D01*
G01Y-130000D02*
X474200D01*
G01X478800Y-128800D02*
X479400Y-129467D01*
X480100Y-129867D01*
X481000Y-130000D01*
X481900Y-129733D01*
X482600Y-129200D01*
X483100Y-128267D01*
X483200Y-127200D01*
X483000Y-126133D01*
X482500Y-125467D01*
X481800Y-124933D01*
X481100Y-124800D01*
X480400Y-124933D01*
X479500Y-125467D01*
X479800Y-122000D01*
X482500D01*
G01X491139Y1015941D02*
X490509Y1016411D01*
X490194Y1016959D01*
X490089Y1017586D01*
X490299Y1018369D01*
X490824Y1018917D01*
X491454Y1019074D01*
X492084Y1018996D01*
X492609Y1018682D01*
X493659Y1017116D01*
X494394Y1016411D01*
X495444Y1015941D01*
X496389Y1015784D01*
Y1019074D01*
G01X490089Y1023729D02*
X490299Y1023102D01*
X490824Y1022632D01*
X491454Y1022319D01*
X492294Y1022084D01*
X493239Y1022006D01*
X494184Y1022084D01*
X495024Y1022319D01*
X495654Y1022632D01*
X496179Y1023102D01*
X496389Y1023729D01*
X496179Y1024356D01*
X495654Y1024826D01*
X495024Y1025139D01*
X494184Y1025374D01*
X493239Y1025452D01*
X492294Y1025374D01*
X491454Y1025139D01*
X490824Y1024826D01*
X490299Y1024356D01*
X490089Y1023729D01*
G01X496389Y1030029D02*
X496284Y1030577D01*
X495969Y1031204D01*
X495444Y1031596D01*
X494709Y1031752D01*
X493974Y1031596D01*
X493344Y1031126D01*
X493029Y1030421D01*
Y1029637D01*
X492819Y1029167D01*
X492294Y1028776D01*
X491559Y1028619D01*
X490824Y1028854D01*
X490299Y1029402D01*
X490089Y1030029D01*
X490299Y1030656D01*
X490824Y1031204D01*
X491559Y1031439D01*
X492294Y1031282D01*
X492819Y1030891D01*
X493029Y1030421D01*
Y1029637D01*
X493344Y1028932D01*
X493974Y1028462D01*
X494709Y1028306D01*
X495444Y1028462D01*
X495969Y1028854D01*
X496284Y1029481D01*
X496389Y1030029D01*
G01X493764Y1034841D02*
X493029Y1035389D01*
X492609Y1035859D01*
X492399Y1036486D01*
X492609Y1037034D01*
X493029Y1037426D01*
X493659Y1037739D01*
X494394Y1037817D01*
X495024Y1037739D01*
X495654Y1037426D01*
X496179Y1036956D01*
X496389Y1036407D01*
X496179Y1035781D01*
X495549Y1035232D01*
X494604Y1034919D01*
X493554Y1034841D01*
X492189Y1034997D01*
X491454Y1035232D01*
X490719Y1035624D01*
X490194Y1036172D01*
X490089Y1036721D01*
X490299Y1037269D01*
X490824Y1037661D01*
G01X493764Y1041141D02*
X493029Y1041689D01*
X492609Y1042159D01*
X492399Y1042786D01*
X492609Y1043334D01*
X493029Y1043726D01*
X493659Y1044039D01*
X494394Y1044117D01*
X495024Y1044039D01*
X495654Y1043726D01*
X496179Y1043256D01*
X496389Y1042707D01*
X496179Y1042081D01*
X495549Y1041532D01*
X494604Y1041219D01*
X493554Y1041141D01*
X492189Y1041297D01*
X491454Y1041532D01*
X490719Y1041924D01*
X490194Y1042472D01*
X490089Y1043021D01*
X490299Y1043569D01*
X490824Y1043961D01*
G01X496599Y1048929D02*
X496494Y1048772D01*
X496284D01*
X496179Y1048929D01*
X496284Y1049086D01*
X496494D01*
X496599Y1048929D01*
G01X496389Y1055229D02*
X490089D01*
X491349Y1054289D01*
G01X496389D02*
Y1056169D01*
G01Y1062469D02*
X490089D01*
X494604Y1059571D01*
Y1063487D01*
G01X730168Y2032159D02*
X974577D01*
Y1748144D01*
X730168D01*
Y2032159D01*
G01X777412Y1883734D02*
G03I-5906J0D01*
G01X778829Y1982237D02*
G03I-7874J0D01*
G01X785680Y1810506D02*
X795128D01*
G02Y1802632I0J-3937D01*
G01X785680D01*
G01X814813Y1810506D02*
X824262D01*
G01X814813D02*
G03Y1802632I0J-3937D01*
G01X824262D01*
M02*
